G04 ================== begin FILE IDENTIFICATION RECORD ==================*
G04 Layout Name:  x887571-005_osp.brd*
G04 Film Name:    bot*
G04 File Format:  Gerber RS274X*
G04 File Origin:  Cadence Allegro 16.3-S036*
G04 Origin Date:  Thu Jul 03 00:06:57 2014*
G04 *
G04 Layer:  VIA CLASS/BOTTOM*
G04 Layer:  PIN/BOTTOM*
G04 Layer:  ETCH/BOTTOM*
G04 Layer:  DRAWING FORMAT/COMMON TEXT*
G04 Layer:  BOARD GEOMETRY/BOT LAYER TEXT*
G04 *
G04 Offset:    (0.0000 0.0000)*
G04 Mirror:    No*
G04 Mode:      Positive*
G04 Rotation:  0*
G04 FullContactRelief:  No*
G04 UndefLineWidth:     4.0000*
G04 ================== end FILE IDENTIFICATION RECORD ====================*
%FSLAX25Y25*MOIN*%
%IR0*IPPOS*OFA0.00000B0.00000*MIA0B0*SFA1.00000B1.00000*%
%ADD19C,.02*%
%ADD16R,.032X.197*%
%ADD14C,.04*%
%ADD13C,.022*%
%ADD20C,.05*%
%ADD12C,.032*%
%ADD23C,.061*%
%ADD26C,.044*%
%ADD11C,.026*%
%ADD27C,.027*%
%ADD15C,.054*%
%ADD18R,.032X.032*%
%ADD24C,.058*%
%ADD29C,.079*%
%ADD22R,.054X.054*%
%ADD25R,.079X.079*%
%ADD21C,.22*%
%ADD28C,.15*%
%ADD17R,.372X.248*%
%ADD10C,.276*%
%ADD30C,.01*%
%ADD31C,.012*%
%ADD32C,.013*%
%ADD33C,.015*%
%ADD34C,.004*%
%ADD35C,.005*%
%ADD36C,.006*%
%ADD37C,.0042*%
%ADD38C,.007*%
%ADD39C,.008*%
%ADD41C,.032*%
%ADD45C,.052*%
%ADD47C,.08*%
%ADD44C,.063*%
%ADD43C,.073*%
%ADD42C,.074*%
%ADD50C,.098*%
%ADD51C,.099*%
%ADD48C,.130001*%
%ADD53R,.073X.073*%
%ADD40C,.154001*%
%ADD49C,.186001*%
%ADD46R,.098X.098*%
%ADD52R,.099X.099*%
G75*
%LPD*%
G75*
G36*
G01X-1629206Y-167953D02*
G03X-1661125Y-161079I-16700J0D01*
G01Y-174827D01*
G03X-1629206Y-167953I15220J6874D01*
G37*
G36*
G01X-1619700Y-159300D02*
X-1629200Y-149800D01*
Y-135900D01*
X-1638200Y-126900D01*
X-1643500D01*
X-1643550Y-126850D01*
X-1646148D01*
G03X-1646638Y-126896I0J-2650D01*
G01X-1646661Y-126900D01*
X-1648987D01*
X-1649010Y-126896D01*
G03X-1649500Y-126850I-490J-2604D01*
G01X-1651200D01*
G03X-1651690Y-126896I0J-2650D01*
G01X-1651713Y-126900D01*
X-1651900D01*
X-1654400Y-124400D01*
Y-118000D01*
X-1652700Y-116300D01*
X-1651559D01*
X-1651488Y-116365D01*
G03X-1650289Y-117094I2488J2739D01*
G02Y-118032I-174J-469D01*
G03X-1647711I1289J-3468D01*
G02Y-117094I174J469D01*
G03X-1646443Y-116300I-1289J3468D01*
G01X-1630900D01*
X-1620900Y-126300D01*
Y-150500D01*
X-1618200Y-153200D01*
X-1617315D01*
X-1617257Y-153233D01*
G03X-1614712I1273J2210D01*
G01X-1614654Y-153200D01*
X-1613800D01*
X-1611800Y-155200D01*
Y-157300D01*
X-1613800Y-159300D01*
X-1619700D01*
G37*
G36*
G01X-1439241Y-17500D02*
Y9213D01*
G02X-1432598Y15855I6643J0D01*
G01X-1421918D01*
G02X-1421461Y15152I0J-500D01*
G03X-1418539I1461J-652D01*
G02X-1418082Y15855I457J204D01*
G01X-1397166D01*
G02X-1396773Y15045I0J-500D01*
G03X-1394263I1255J-992D01*
G02X-1393871Y15855I392J310D01*
G01X-1371918D01*
G02X-1371461Y15152I0J-500D01*
G03X-1368539I1461J-652D01*
G02X-1368082Y15855I457J204D01*
G01X-1346918D01*
G02X-1346461Y15152I0J-500D01*
G03X-1343539I1461J-652D01*
G02X-1343082Y15855I457J204D01*
G01X-1321918D01*
G02X-1321461Y15152I0J-500D01*
G03X-1318539I1461J-652D01*
G02X-1318082Y15855I457J204D01*
G01X-1296918D01*
G02X-1296461Y15152I0J-500D01*
G03X-1293539I1461J-652D01*
G02X-1293082Y15855I457J204D01*
G01X-1287352D01*
G02X-1286998Y15002I0J-500D01*
G01X-1357150Y-55150D01*
X-1449250D01*
X-1453200Y-59100D01*
X-1616700D01*
X-1618900Y-56900D01*
Y-22800D01*
X-1617200Y-21100D01*
Y16400D01*
X-1616509Y17080D01*
X-1542110D01*
Y-20990D01*
X-1538100Y-25000D01*
X-1462000D01*
X-1460000Y-23000D01*
X-1444741D01*
X-1439241Y-17500D01*
G37*
G36*
G01X-1506028Y-154950D02*
G02I-16700J0D01*
G37*
G36*
G01X-1462300Y16900D02*
Y-22000D01*
X-1463500Y-23200D01*
X-1536500D01*
X-1539300Y-20400D01*
Y16900D01*
X-1462300D01*
G37*
G36*
G01X-1455800Y-184500D02*
Y-89000D01*
X-1452300Y-85500D01*
X-1442500D01*
X-1431900Y-74900D01*
X-1414113D01*
X-1414095Y-75130D01*
G03X-1410905I1595J130D01*
G01X-1410887Y-74900D01*
X-1389113D01*
X-1389095Y-75130D01*
G03X-1385905I1595J130D01*
G01X-1385887Y-74900D01*
X-1364113D01*
X-1364095Y-75130D01*
G03X-1360905I1595J130D01*
G01X-1360887Y-74900D01*
X-1350700D01*
X-1320300Y-105300D01*
X-1292500D01*
X-1289300Y-108500D01*
Y-184500D01*
X-1455800D01*
G37*
G36*
G01X-1020000Y-31500D02*
X-1049650Y-61150D01*
X-1049737Y-61161D01*
G03X-1051657Y-61494I2061J-17580D01*
G01X-1051684Y-61500D01*
X-1056000D01*
X-1065300Y-70800D01*
Y-77102D01*
X-1065301Y-77113D01*
G03Y-80367I17625J-1627D01*
G01X-1065300Y-80379D01*
Y-91400D01*
X-1067400Y-93500D01*
X-1081374D01*
X-1081424Y-93316D01*
G03X-1088852I-3714J-1015D01*
G01X-1088902Y-93500D01*
X-1125400D01*
X-1129839Y-89061D01*
G02X-1129486Y-88207I354J354D01*
G01X-1123860D01*
Y-78407D01*
X-1133660D01*
Y-85150D01*
X-1147750D01*
X-1151125Y-88525D01*
X-1162850Y-76800D01*
Y-73489D01*
X-1162840Y-73455D01*
G03X-1176853Y-52064I-16136J4715D01*
G03X-1184077Y-52722I-2123J-16676D01*
G03X-1195713Y-70319I5101J-16018D01*
G03X-1195421Y-72230I16737J1579D01*
G03X-1195278Y-72849I16445J3490D01*
G01X-1195270Y-72879D01*
Y-75870D01*
X-1211800Y-92400D01*
X-1261403D01*
X-1268203Y-85600D01*
X-1297403D01*
X-1300103Y-82900D01*
X-1301342D01*
G03X-1303562Y-83000I-1058J-1200D01*
G01X-1316500D01*
X-1323500Y-76000D01*
Y-39500D01*
X-1314568Y-30568D01*
G02X-1313729Y-30805I354J-354D01*
G03X-1310595Y-27671I2529J605D01*
G02X-1310832Y-26832I116J486D01*
G01X-1297737Y-13737D01*
G02X-1296911Y-13926I354J-354D01*
G03X-1294874Y-11889I1511J526D01*
G02X-1295063Y-11063I164J472D01*
G01X-1278200Y5800D01*
X-1201598D01*
G02X-1201098Y5324I0J-500D01*
G03X-1197902I1598J76D01*
G02X-1197402Y5800I499J-24D01*
G01X-1023300D01*
X-1020000Y2500D01*
Y-31500D01*
G37*
G36*
G01X-1030976Y-78740D02*
G03I-16700J0D01*
G37*
G36*
G01X-830638Y5500D02*
X-824600D01*
G02X-824100Y5000I0J-500D01*
G03X-820900I1600J0D01*
G02X-820400Y5500I500J0D01*
G01X-799600D01*
G02X-799100Y5000I0J-500D01*
G03X-795900I1600J0D01*
G02X-795400Y5500I500J0D01*
G01X-774600D01*
G02X-774100Y5000I0J-500D01*
G03X-770900I1600J0D01*
G02X-770400Y5500I500J0D01*
G01X-749600D01*
G02X-749100Y5000I0J-500D01*
G03X-745900I1600J0D01*
G02X-745400Y5500I500J0D01*
G01X-724600D01*
G02X-724100Y5000I0J-500D01*
G03X-720900I1600J0D01*
G02X-720400Y5500I500J0D01*
G01X-699600D01*
G02X-699100Y5000I0J-500D01*
G03X-695900I1600J0D01*
G02X-695400Y5500I500J0D01*
G01X-674600D01*
G02X-674100Y5000I0J-500D01*
G03X-670900I1600J0D01*
G02X-670400Y5500I500J0D01*
G01X-621500D01*
X-609000Y-7000D01*
X-516500D01*
X-465500Y-58000D01*
Y-86451D01*
X-439500Y-112451D01*
X-420849D01*
X-418500Y-114800D01*
Y-184400D01*
X-418700Y-184600D01*
X-583000D01*
Y-61500D01*
X-587500Y-57000D01*
X-716500D01*
X-750150Y-90650D01*
Y-140850D01*
X-751652Y-142352D01*
X-791706D01*
G02X-791950Y-141416I0J500D01*
G03X-795507I-1779J3187D01*
G02X-795751Y-142352I-244J-437D01*
G01X-798852D01*
X-812599Y-156100D01*
Y-181299D01*
X-813100Y-181800D01*
X-930500D01*
Y-48600D01*
X-951400Y-27700D01*
X-951500Y-27800D01*
X-1004800D01*
X-1004900Y-27700D01*
Y5500D01*
X-924600D01*
G02X-924100Y5000I0J-500D01*
G03X-920900I1600J0D01*
G02X-920400Y5500I500J0D01*
G01X-899600D01*
G02X-899100Y5000I0J-500D01*
G03X-895900I1600J0D01*
G02X-895400Y5500I500J0D01*
G01X-874600D01*
G02X-874100Y5000I0J-500D01*
G03X-870900I1600J0D01*
G02X-870400Y5500I500J0D01*
G01X-849600D01*
G02X-849100Y5000I0J-500D01*
G03X-845900I1600J0D01*
G02X-845400Y5500I500J0D01*
G01X-841362D01*
G02X-840979Y4679I0J-500D01*
G03X-831021I4979J-4179D01*
G02X-830638Y5500I383J321D01*
G37*
G36*
G01X-798500Y-167800D02*
X-799700Y-166600D01*
Y-158000D01*
X-798200Y-156500D01*
X-796434D01*
G03X-795017Y-157445I2706J2523D01*
G02Y-158382I-174J-469D01*
G03X-792440I1289J-3468D01*
G02Y-157445I174J469D01*
G03X-791022Y-156500I-1289J3468D01*
G01X-789200D01*
X-786800Y-154100D01*
X-743900D01*
X-742600Y-155400D01*
Y-158000D01*
X-744200Y-159600D01*
X-745188D01*
X-745221Y-159591D01*
G03X-746590I-685J-2456D01*
G01X-746623Y-159600D01*
X-752900D01*
X-761100Y-167800D01*
X-798500D01*
G37*
G36*
G01X-668697Y-150370D02*
G02Y-159531I16060J-4581D01*
G01Y-150370D01*
G37*
G36*
G01X-390900Y-95200D02*
X-408700Y-77400D01*
X-413500D01*
X-415400Y-75500D01*
X-415700D01*
Y15300D01*
X-209700D01*
Y-90000D01*
X-258701D01*
X-268300Y-80401D01*
X-276201D01*
X-283700Y-87900D01*
Y-94700D01*
X-284200Y-95200D01*
X-290076D01*
G02X-290570Y-94622I0J500D01*
G03X-290394Y-92362I-14391J2260D01*
G01Y-77132D01*
G03X-319528I-14567J8391D01*
G01Y-92362D01*
G03X-319351Y-94622I14567J0D01*
G02X-319845Y-95200I-494J-78D01*
G01X-390900D01*
G37*
G36*
G01X-160897Y-78740D02*
G02I-16700J0D01*
G37*
G36*
G01D02*
G02I-16700J0D01*
G37*
G36*
G01X19000Y-156600D02*
G03X17600Y-180700I-11973J-11395D01*
G01X19000Y-178100D01*
Y-156600D01*
G37*
%LPC*%
G75*
G36*
G01X-1347998Y-116208D02*
G02X-1347689Y-120301I-8891J-2729D01*
G02X-1347998Y-116208I-9199J1364D01*
G37*
G36*
G01X-1408504Y-130439D02*
Y-145669D01*
G02X-1437638I-14567J0D01*
G01Y-130439D01*
G02X-1408504Y-130439I14567J8391D01*
G37*
G36*
G01X-1347998Y-169894D02*
G02Y-164437I-8891J2729D01*
G02Y-169894I-8891J-2729D01*
G37*
G36*
G01X-1306597Y-147362D02*
G02X-1308489Y-144838I-5412J-2087D01*
G03X-1307698Y-144333I303J397D01*
G02X-1305890Y-146743I3564J789D01*
G03X-1306597Y-147362I-240J-438D01*
G37*
G36*
G01X-1297139Y-38747D02*
G02X-1299448Y-39040I-861J-2453D01*
G03X-1299561Y-38153I-278J415D01*
G02X-1297252Y-37860I861J2453D01*
G03X-1297139Y-38747I278J-415D01*
G37*
G36*
G01X-546299Y-100754D02*
Y-115984D01*
G02X-575433I-14567J0D01*
G01Y-100754D01*
G02X-546299Y-100754I14567J8391D01*
G37*
G36*
G01X-490095Y-158465D02*
G03X-490143Y-157514I-177J468D01*
G02X-483477I3333J12514D01*
G03X-483525Y-158465I129J-483D01*
G02X-490095I-3285J-8701D01*
G37*
G36*
G01X-445448Y-144838D02*
G02X-447341Y-147362I3519J-4611D01*
G03X-448048Y-146743I-467J180D01*
G02X-446240Y-144333I-1756J3200D01*
G03X-445448Y-144838I488J-108D01*
G37*
G36*
G01X-909007Y-158151D02*
G03X-908880Y-158357I477J151D01*
G02X-911120I-1120J-1143D01*
G03X-910993Y-158151I-350J357D01*
G01X-910981Y-158114D01*
Y-157826D01*
X-928470D01*
Y-157500D01*
X-929000D01*
Y-141000D01*
X-827500D01*
Y-157500D01*
X-827770D01*
Y-157826D01*
X-834019D01*
Y-158114D01*
X-834007Y-158151D01*
G03X-833880Y-158357I477J151D01*
G02X-836120I-1120J-1143D01*
G03X-835993Y-158151I-350J357D01*
G01X-835981Y-158114D01*
Y-157826D01*
X-859019D01*
Y-158114D01*
X-859007Y-158151D01*
G03X-858880Y-158357I477J151D01*
G02X-861120I-1120J-1143D01*
G03X-860993Y-158151I-350J357D01*
G01X-860981Y-158114D01*
Y-157826D01*
X-884019D01*
Y-158114D01*
X-884007Y-158151D01*
G03X-883880Y-158357I477J151D01*
G02X-886120I-1120J-1143D01*
G03X-885993Y-158151I-350J357D01*
G01X-885981Y-158114D01*
Y-157826D01*
X-909019D01*
Y-158114D01*
X-909007Y-158151D01*
G37*
G54D41*
X-1435000Y1000D03*
X-1419500Y-18000D03*
X-1394500D03*
X-1395000Y-500D03*
X-1382500Y-8000D03*
Y7000D03*
X-1356700Y-25600D03*
X-1357500Y-8000D03*
X-1370000Y-500D03*
X-1357500Y7000D03*
X-1345000Y-500D03*
X-1332500Y-27500D03*
Y7000D03*
X-1320000Y-500D03*
X-1318500Y-6000D03*
X-1307500Y7000D03*
X-1373800Y-52900D03*
X-1450000Y-175000D03*
X-1437500Y-162500D03*
X-1450000Y-150000D03*
Y-125000D03*
X-1443500Y-94000D03*
X-1450000Y-100000D03*
X-1425000Y-175000D03*
X-1424500Y-100000D03*
X-1425000Y-87500D03*
X-1412500Y-162500D03*
X-1412000Y-87000D03*
X-1400000Y-175000D03*
X-1387500Y-162500D03*
X-1400000Y-150000D03*
X-1387500Y-137500D03*
X-1400000Y-125000D03*
X-1387500Y-112500D03*
X-1400500Y-87000D03*
X-1391000Y-96500D03*
X-1061900Y-5200D03*
X-1062000Y-29200D03*
X-1063600Y-56600D03*
X-1100000Y-2500D03*
X-1111500D03*
Y-15000D03*
X-1107800Y-68200D03*
X-1107700Y-63100D03*
Y-73400D03*
X-1126000Y-2500D03*
Y-15000D03*
X-1137500Y-2500D03*
Y-15000D03*
X-1160000Y-38500D03*
X-1178800Y-5800D03*
X-1171500Y-21750D03*
X-1172000Y-10750D03*
X-1177800Y-12100D03*
X-1178800Y-34800D03*
X-1172500Y-38500D03*
X-1179000Y-40500D03*
X-1178900Y-46700D03*
X-1173200Y-49700D03*
X-1172500Y-44000D03*
X-1192359Y-5800D03*
X-1191000Y-18250D03*
X-1191500Y-34000D03*
X-1191200Y-40500D03*
X-1199500Y-3000D03*
X-1232500Y-20000D03*
X-1245000D03*
Y-45000D03*
X-1232500Y-57500D03*
X-1245000Y-70000D03*
X-1257500Y-20000D03*
Y-45000D03*
Y-57500D03*
X-1298800Y-30200D03*
X-1298400Y-63200D03*
X-1297995Y-58405D03*
X-1293500Y-80000D03*
X-1310600Y-46690D03*
X-1310559Y-68700D03*
X-1317700Y-60200D03*
X-1313040Y-80810D03*
X-983000Y-7500D03*
X-957500D03*
X-922500Y-170000D03*
Y-120000D03*
Y-95000D03*
Y-70000D03*
Y-45000D03*
Y-20000D03*
X-910000Y-132500D03*
Y-107500D03*
Y-82500D03*
Y-57500D03*
Y-7500D03*
X-897500Y-170000D03*
X-885000Y-132500D03*
Y-107500D03*
X-897500Y-95000D03*
X-885000Y-82500D03*
X-897500Y-70000D03*
X-885000Y-57500D03*
X-897500Y-45000D03*
X-885000Y-7500D03*
X-897500Y-20000D03*
X-872500Y-170000D03*
Y-95000D03*
Y-70000D03*
Y-45000D03*
Y-20000D03*
X-860000Y-132500D03*
Y-107500D03*
Y-82500D03*
Y-57500D03*
Y-7500D03*
X-847500Y-170000D03*
Y-95000D03*
Y-70000D03*
Y-45000D03*
Y-20000D03*
X-822500Y-170000D03*
Y-145000D03*
X-835000Y-132500D03*
X-822500Y-120000D03*
X-835000Y-107500D03*
X-822500Y-95000D03*
X-835000Y-82500D03*
X-822500Y-70000D03*
X-835000Y-57500D03*
X-822500Y-45000D03*
Y-20000D03*
X-810000Y-145000D03*
Y-132500D03*
Y-120000D03*
Y-70000D03*
Y-57500D03*
Y-45000D03*
Y-7500D03*
X-797500Y-120000D03*
Y-70000D03*
Y-57500D03*
Y-45000D03*
Y-20000D03*
X-785500Y-120000D03*
X-785000Y-70000D03*
Y-57500D03*
Y-45000D03*
Y-7500D03*
X-760000Y-132500D03*
X-772500Y-120000D03*
X-760000Y-107500D03*
X-772500Y-95000D03*
X-760000Y-82500D03*
X-772500Y-70000D03*
X-760000Y-57500D03*
X-772500Y-45000D03*
X-760000Y-7500D03*
X-772500Y-20000D03*
X-747500Y-45000D03*
Y-20000D03*
X-735000Y-57500D03*
Y-7500D03*
X-722500Y-45000D03*
Y-20000D03*
X-697500Y-45000D03*
Y-20000D03*
X-710000Y-7500D03*
X-685000D03*
X-672500Y-45000D03*
Y-20000D03*
X-655500Y-37500D03*
Y-12500D03*
Y-500D03*
X-616000Y-37500D03*
X-630000Y-25500D03*
Y-12500D03*
X-616000D03*
X-602500Y-37500D03*
Y-12500D03*
X-590000Y-25000D03*
X-577500Y-177500D03*
Y-152500D03*
Y-127500D03*
Y-37500D03*
Y-12500D03*
X-565000Y-165000D03*
Y-140000D03*
Y-65000D03*
Y-25000D03*
X-540000Y-165000D03*
X-552500Y-177500D03*
Y-152500D03*
X-540000Y-140000D03*
Y-115000D03*
Y-90000D03*
Y-65000D03*
Y-25000D03*
X-552500Y-37500D03*
Y-12500D03*
X-527500Y-177500D03*
Y-152500D03*
Y-127500D03*
Y-102500D03*
Y-77500D03*
Y-37500D03*
Y-12500D03*
X-515000Y-165000D03*
Y-140000D03*
Y-115000D03*
Y-90000D03*
Y-65000D03*
Y-25000D03*
X-502500Y-102500D03*
X-490000Y-90000D03*
X-502500Y-77500D03*
Y-37500D03*
X-321700Y-42000D03*
X-322400Y-31000D03*
X-321300Y-24950D03*
X-321800Y-7300D03*
X-321700Y-13628D03*
X-321859Y-1500D03*
X-303200Y-43300D03*
Y-48800D03*
X-309400Y-47700D03*
X-302300Y-25950D03*
X-302900Y-37900D03*
X-309400Y-25100D03*
X-308500Y-36400D03*
X-308800Y-7400D03*
X-307900Y-13628D03*
X-302300Y-4450D03*
X-290400Y-43200D03*
X-290700Y-9750D03*
X-290300Y-4400D03*
G54D45*
X-1047300Y-2700D03*
X-1054600Y-5100D03*
X-1047289Y-26300D03*
X-1054900Y-29800D03*
X-1051200Y-44100D03*
X-1056900Y-56300D03*
X-1100000Y-15000D03*
X-1159700Y-5750D03*
X-1151500Y-15000D03*
X-1158700Y-16250D03*
X-1160150Y-26750D03*
X-1178950Y-23250D03*
X-1191000Y-46500D03*
X-1232500Y-45000D03*
X-1298780Y-52200D03*
X-932500Y-7500D03*
X-321500Y-47500D03*
X-302500Y-15200D03*
X-289500Y-32500D03*
X-290800Y-26000D03*
G54D47*
X-1207677Y-6142D03*
Y-41575D03*
X-1282480Y-23858D03*
Y-59291D03*
X-1207677Y-77008D03*
G54D44*
X-1025000Y1459D03*
X-981693D03*
X-938386D03*
G54D43*
X-1304134Y-175039D03*
X-1296260Y-167165D03*
X-1304134D03*
X-1296260Y-159291D03*
X-1304134D03*
X-1296260Y-143543D03*
Y-135669D03*
X-1304134D03*
X-1296260Y-127795D03*
X-1304134D03*
X-457677Y-175039D03*
Y-167165D03*
Y-159291D03*
Y-143543D03*
Y-135669D03*
X-449803Y-175039D03*
Y-167165D03*
Y-159291D03*
Y-135669D03*
Y-127795D03*
G54D42*
X-1296260Y-175039D03*
G54D50*
X-806854Y-99635D03*
X-785200D03*
G54D51*
X-806854Y-83100D03*
G54D48*
X-836000Y-172000D03*
G54D53*
X-457677Y-127795D03*
G54D40*
X-1410000Y0D03*
G54D49*
X-486810Y-118937D03*
G54D46*
X-1085138Y-4567D03*
Y-43937D03*
Y-83307D03*
X-1107500D03*
X-1118917Y-4567D03*
X-1141240Y-24252D03*
Y-63622D03*
G54D52*
X-785200Y-83100D03*
%LPD*%
G75*
G36*
G01X-903782Y-186850D02*
Y-184850D01*
X-865782D01*
Y-186850D01*
X-903782D01*
G37*
G54D10*
X-1645906Y-167953D03*
X-1522728Y-154950D03*
X-1047676Y-78740D03*
X-652638Y-154950D03*
X-177597Y-78740D03*
X6890Y-167953D03*
G54D11*
X-1656906D03*
X-1645906Y-178953D03*
X-1653906Y-175453D03*
X-1653406Y-159953D03*
X-1645906Y-156953D03*
X-1634906Y-167953D03*
X-1637906Y-175453D03*
X-1638406Y-159953D03*
X-1530728Y-162450D03*
X-1533728Y-154950D03*
X-1530228Y-146950D03*
X-1522728Y-165950D03*
X-1514728Y-162450D03*
X-1515228Y-146950D03*
X-1522728Y-143950D03*
X-1511728Y-154950D03*
X-1058676Y-78740D03*
X-1047676Y-89740D03*
X-1055676Y-86240D03*
X-1055176Y-70740D03*
X-1047676Y-67740D03*
X-1039676Y-86240D03*
X-1040176Y-70740D03*
X-1036676Y-78740D03*
X-663638Y-154950D03*
X-652638Y-165950D03*
X-660638Y-162450D03*
X-660138Y-146950D03*
X-652638Y-143950D03*
X-641638Y-154950D03*
X-644638Y-162450D03*
X-645138Y-146950D03*
X-177597Y-89740D03*
X-185597Y-86240D03*
X-188597Y-78740D03*
X-185097Y-70740D03*
X-177597Y-67740D03*
X-169597Y-86240D03*
X-170097Y-70740D03*
X-166597Y-78740D03*
X-4110Y-167953D03*
X6890Y-178953D03*
X-1110Y-175453D03*
X14390Y-159953D03*
X-610D03*
X6890Y-156953D03*
X17890Y-167953D03*
X14890Y-175453D03*
G54D20*
X-1410000Y0D03*
X-1356889Y-167165D03*
Y-118937D03*
X-1312008Y-149449D03*
X-1278150Y-142362D03*
X-1212008D03*
X-1132087Y-126220D03*
X-1094291D03*
X-1051613Y-167165D03*
Y-118937D03*
X-486810Y-167165D03*
Y-118937D03*
X-441929Y-149449D03*
X-408071Y-142362D03*
X-341929D03*
X-262008Y-126220D03*
X-224213D03*
X-181534Y-167165D03*
Y-118937D03*
X0Y-136453D03*
X0Y0D03*
G54D30*
G01X-1184000Y-502500D02*
Y-512500D01*
G01X-1186683Y-502500D02*
X-1181317D01*
G01X-1176833Y-512500D02*
Y-502500D01*
X-1173917D01*
X-1172983Y-503000D01*
X-1172400Y-503667D01*
X-1172167Y-505000D01*
X-1172400Y-506333D01*
X-1173100Y-507167D01*
X-1173917Y-507667D01*
X-1176833D01*
G01X-1173917D02*
X-1172167Y-512500D01*
G01X-1167917D02*
X-1165000Y-502500D01*
X-1162083Y-512500D01*
G01X-1163133Y-509000D02*
X-1166867D01*
G01X-1155500Y-512500D02*
Y-508000D01*
X-1157833Y-502500D01*
G01X-1153167D02*
X-1155500Y-508000D01*
G01X-1135567Y-507167D02*
X-1135100Y-506667D01*
X-1134750Y-505834D01*
X-1134517Y-504667D01*
X-1134750Y-503667D01*
X-1135217Y-503000D01*
X-1136033Y-502500D01*
X-1139183D01*
Y-512500D01*
X-1135333D01*
X-1134517Y-511833D01*
X-1134050Y-510833D01*
X-1133817Y-509667D01*
X-1134050Y-508500D01*
X-1134750Y-507500D01*
X-1135567Y-507167D01*
X-1139183D01*
G01X-1129917Y-512500D02*
X-1127000Y-502500D01*
X-1124083Y-512500D01*
G01X-1125133Y-509000D02*
X-1128867D01*
G01X-1114933Y-503333D02*
X-1115633Y-502833D01*
X-1116450Y-502500D01*
X-1117383D01*
X-1118433Y-503000D01*
X-1119250Y-503833D01*
X-1119833Y-504833D01*
X-1120300Y-506500D01*
X-1120417Y-508000D01*
X-1120183Y-509500D01*
X-1119833Y-510500D01*
X-1119133Y-511500D01*
X-1118317Y-512167D01*
X-1117500Y-512500D01*
X-1116683D01*
X-1115867Y-512167D01*
X-1115167Y-511667D01*
X-1114583Y-511000D01*
G01X-1110567Y-512500D02*
Y-502500D01*
G01X-1106133D02*
X-1110567Y-508667D01*
G01X-1105433Y-512500D02*
X-1108583Y-505834D01*
G01X-1100833Y-512500D02*
Y-502500D01*
X-1098033D01*
X-1097100Y-503000D01*
X-1096400Y-504167D01*
X-1096167Y-505500D01*
X-1096400Y-506833D01*
X-1096983Y-507833D01*
X-1098033Y-508334D01*
X-1100833D01*
G01X-1091333Y-502500D02*
Y-512500D01*
X-1086667D01*
G01X-1082417D02*
X-1079500Y-502500D01*
X-1076583Y-512500D01*
G01X-1077633Y-509000D02*
X-1081367D01*
G01X-1072683Y-512500D02*
Y-502500D01*
X-1067317Y-512500D01*
Y-502500D01*
G01X-1058167Y-512500D02*
X-1062833D01*
Y-502500D01*
X-1058167D01*
G01X-1060033Y-507333D02*
X-1062833D01*
G01X-1043717Y-512500D02*
Y-502500D01*
X-1039283D01*
G01X-1040917Y-507333D02*
X-1043717D01*
G01X-1034917Y-512500D02*
X-1032000Y-502500D01*
X-1029083Y-512500D01*
G01X-1030133Y-509000D02*
X-1033867D01*
G01X-1021567Y-507167D02*
X-1021100Y-506667D01*
X-1020750Y-505834D01*
X-1020517Y-504667D01*
X-1020750Y-503667D01*
X-1021217Y-503000D01*
X-1022033Y-502500D01*
X-1025183D01*
Y-512500D01*
X-1021333D01*
X-1020517Y-511833D01*
X-1020050Y-510833D01*
X-1019817Y-509667D01*
X-1020050Y-508500D01*
X-1020750Y-507500D01*
X-1021567Y-507167D01*
X-1025183D01*
G01X-1002567D02*
X-1002100Y-506667D01*
X-1001750Y-505834D01*
X-1001517Y-504667D01*
X-1001750Y-503667D01*
X-1002217Y-503000D01*
X-1003033Y-502500D01*
X-1006183D01*
Y-512500D01*
X-1002333D01*
X-1001517Y-511833D01*
X-1001050Y-510833D01*
X-1000817Y-509667D01*
X-1001050Y-508500D01*
X-1001750Y-507500D01*
X-1002567Y-507167D01*
X-1006183D01*
G01X-985083Y-515833D02*
X-986250Y-514167D01*
X-986833Y-512500D01*
Y-505834D01*
X-986250Y-504167D01*
X-985083Y-502500D01*
G01X-975000Y-512500D02*
X-975933Y-512333D01*
X-976750Y-511667D01*
X-977450Y-510667D01*
X-977917Y-509500D01*
X-978150Y-508167D01*
Y-506833D01*
X-977917Y-505500D01*
X-977450Y-504333D01*
X-976750Y-503333D01*
X-975933Y-502667D01*
X-975000Y-502500D01*
X-974067Y-502667D01*
X-973250Y-503333D01*
X-972550Y-504333D01*
X-972083Y-505500D01*
X-971850Y-506833D01*
Y-508167D01*
X-972083Y-509500D01*
X-972550Y-510667D01*
X-973250Y-511667D01*
X-974067Y-512333D01*
X-975000Y-512500D01*
G01X-967950Y-511167D02*
X-967017Y-512000D01*
X-965967Y-512500D01*
X-965033D01*
X-964100Y-512000D01*
X-963400Y-511167D01*
X-963050Y-510000D01*
X-963283Y-508834D01*
X-963867Y-507833D01*
X-964917Y-507167D01*
X-966317Y-506833D01*
X-967133Y-506167D01*
X-967483Y-505000D01*
X-967250Y-503833D01*
X-966667Y-503000D01*
X-965850Y-502500D01*
X-965033D01*
X-964217Y-502833D01*
X-963517Y-503667D01*
G01X-958333Y-512500D02*
Y-502500D01*
X-955533D01*
X-954600Y-503000D01*
X-953900Y-504167D01*
X-953667Y-505500D01*
X-953900Y-506833D01*
X-954483Y-507833D01*
X-955533Y-508334D01*
X-958333D01*
G01X-945917Y-515833D02*
X-944750Y-514167D01*
X-944167Y-512500D01*
Y-505834D01*
X-944750Y-504167D01*
X-945917Y-502500D01*
G01X-830275Y-153159D02*
X-834965Y-143659D01*
G01X-830275D02*
X-834965Y-153159D01*
G01X-841719D02*
X-842501Y-153001D01*
X-843394Y-152526D01*
X-843953Y-151734D01*
X-844176Y-150626D01*
X-843953Y-149517D01*
X-843283Y-148567D01*
X-842278Y-148092D01*
X-841161D01*
X-840491Y-147776D01*
X-839933Y-146984D01*
X-839709Y-145876D01*
X-840045Y-144767D01*
X-840826Y-143976D01*
X-841719Y-143659D01*
X-842613Y-143976D01*
X-843394Y-144767D01*
X-843730Y-145876D01*
X-843506Y-146984D01*
X-842948Y-147776D01*
X-842278Y-148092D01*
X-841161D01*
X-840156Y-148567D01*
X-839486Y-149517D01*
X-839263Y-150626D01*
X-839486Y-151734D01*
X-840045Y-152526D01*
X-840938Y-153001D01*
X-841719Y-153159D01*
G01X-850819D02*
X-851601Y-153001D01*
X-852494Y-152526D01*
X-853053Y-151734D01*
X-853276Y-150626D01*
X-853053Y-149517D01*
X-852383Y-148567D01*
X-851378Y-148092D01*
X-850261D01*
X-849591Y-147776D01*
X-849033Y-146984D01*
X-848809Y-145876D01*
X-849145Y-144767D01*
X-849926Y-143976D01*
X-850819Y-143659D01*
X-851713Y-143976D01*
X-852494Y-144767D01*
X-852830Y-145876D01*
X-852606Y-146984D01*
X-852048Y-147776D01*
X-851378Y-148092D01*
X-850261D01*
X-849256Y-148567D01*
X-848586Y-149517D01*
X-848363Y-150626D01*
X-848586Y-151734D01*
X-849145Y-152526D01*
X-850038Y-153001D01*
X-850819Y-153159D01*
G01X-859696D02*
X-859919Y-151101D01*
X-860255Y-149359D01*
X-860701Y-147776D01*
X-861260Y-146034D01*
X-862153Y-143659D01*
X-857686D01*
G01X-866563Y-151734D02*
X-867233Y-152526D01*
X-868014Y-153001D01*
X-869019Y-153159D01*
X-870025Y-152842D01*
X-870806Y-152209D01*
X-871365Y-151101D01*
X-871476Y-149834D01*
X-871253Y-148567D01*
X-870694Y-147776D01*
X-869913Y-147142D01*
X-869131Y-146984D01*
X-868350Y-147142D01*
X-867345Y-147776D01*
X-867680Y-143659D01*
X-870694D01*
G01X-877896Y-153159D02*
X-878119Y-151101D01*
X-878455Y-149359D01*
X-878901Y-147776D01*
X-879460Y-146034D01*
X-880353Y-143659D01*
X-875886D01*
G01X-887219Y-153159D02*
Y-143659D01*
X-885880Y-145559D01*
G01Y-153159D02*
X-888559D01*
G01X-894868Y-149992D02*
X-897771D01*
G01X-905419Y-143659D02*
X-904526Y-143976D01*
X-903856Y-144767D01*
X-903409Y-145717D01*
X-903075Y-146984D01*
X-902963Y-148409D01*
X-903075Y-149834D01*
X-903409Y-151101D01*
X-903856Y-152051D01*
X-904526Y-152842D01*
X-905419Y-153159D01*
X-906313Y-152842D01*
X-906983Y-152051D01*
X-907430Y-151101D01*
X-907765Y-149834D01*
X-907876Y-148409D01*
X-907765Y-146984D01*
X-907430Y-145717D01*
X-906983Y-144767D01*
X-906313Y-143976D01*
X-905419Y-143659D01*
G01X-914519D02*
X-913626Y-143976D01*
X-912956Y-144767D01*
X-912509Y-145717D01*
X-912175Y-146984D01*
X-912063Y-148409D01*
X-912175Y-149834D01*
X-912509Y-151101D01*
X-912956Y-152051D01*
X-913626Y-152842D01*
X-914519Y-153159D01*
X-915413Y-152842D01*
X-916083Y-152051D01*
X-916530Y-151101D01*
X-916865Y-149834D01*
X-916976Y-148409D01*
X-916865Y-146984D01*
X-916530Y-145717D01*
X-916083Y-144767D01*
X-915413Y-143976D01*
X-914519Y-143659D01*
G01X-921163Y-151734D02*
X-921833Y-152526D01*
X-922614Y-153001D01*
X-923619Y-153159D01*
X-924625Y-152842D01*
X-925406Y-152209D01*
X-925965Y-151101D01*
X-926076Y-149834D01*
X-925853Y-148567D01*
X-925294Y-147776D01*
X-924513Y-147142D01*
X-923731Y-146984D01*
X-922950Y-147142D01*
X-921945Y-147776D01*
X-922280Y-143659D01*
X-925294D01*
G01X-902000Y-470000D02*
Y-460000D01*
X-903400Y-462000D01*
G01Y-470000D02*
X-900600D01*
G01X-892500Y-470333D02*
X-892733Y-470167D01*
Y-469833D01*
X-892500Y-469667D01*
X-892267Y-469833D01*
Y-470167D01*
X-892500Y-470333D01*
G01Y-465834D02*
X-892733Y-465667D01*
Y-465333D01*
X-892500Y-465167D01*
X-892267Y-465333D01*
Y-465667D01*
X-892500Y-465834D01*
G01X-883000Y-470000D02*
Y-460000D01*
X-884400Y-462000D01*
G01Y-470000D02*
X-881600D01*
G01X-785060Y-472187D02*
X-784127Y-473020D01*
X-783077Y-473520D01*
X-782143D01*
X-781210Y-473020D01*
X-780510Y-472187D01*
X-780160Y-471020D01*
X-780393Y-469854D01*
X-780977Y-468853D01*
X-782027Y-468187D01*
X-783427Y-467853D01*
X-784243Y-467187D01*
X-784593Y-466020D01*
X-784360Y-464853D01*
X-783777Y-464020D01*
X-782960Y-463520D01*
X-782143D01*
X-781327Y-463853D01*
X-780627Y-464687D01*
G01X-775560Y-473520D02*
Y-463520D01*
G01X-770660D02*
Y-473520D01*
G01Y-468520D02*
X-775560D01*
G01X-766527Y-473520D02*
X-763610Y-463520D01*
X-760693Y-473520D01*
G01X-761743Y-470020D02*
X-765477D01*
G01X-757610Y-463520D02*
X-755977Y-473520D01*
X-754110Y-463520D01*
X-752243Y-473520D01*
X-750610Y-463520D01*
G01X-668067Y-470500D02*
X-667367Y-471667D01*
X-666433Y-472333D01*
X-665383Y-472500D01*
X-664450Y-472333D01*
X-663517Y-471500D01*
X-662933Y-470500D01*
X-662817Y-469500D01*
X-663050Y-468334D01*
X-663867Y-467500D01*
X-664683Y-467167D01*
X-665733D01*
G01X-664683D02*
X-663983Y-466667D01*
X-663400Y-465834D01*
X-663167Y-464833D01*
X-663400Y-463833D01*
X-663983Y-463000D01*
X-665033Y-462500D01*
X-666083Y-462667D01*
X-667133Y-463333D01*
G01X-656000Y-462500D02*
X-656933Y-462833D01*
X-657633Y-463667D01*
X-658100Y-464667D01*
X-658450Y-466000D01*
X-658567Y-467500D01*
X-658450Y-469000D01*
X-658100Y-470333D01*
X-657633Y-471334D01*
X-656933Y-472167D01*
X-656000Y-472500D01*
X-655067Y-472167D01*
X-654367Y-471334D01*
X-653900Y-470333D01*
X-653550Y-469000D01*
X-653433Y-467500D01*
X-653550Y-466000D01*
X-653900Y-464667D01*
X-654367Y-463667D01*
X-655067Y-462833D01*
X-656000Y-462500D01*
G01X-648017Y-469167D02*
X-644983D01*
G01X-639917Y-472500D02*
X-637000Y-462500D01*
X-634083Y-472500D01*
G01X-635133Y-469000D02*
X-638867D01*
G01X-629833Y-472500D02*
Y-462500D01*
X-627033D01*
X-626100Y-463000D01*
X-625400Y-464167D01*
X-625167Y-465500D01*
X-625400Y-466833D01*
X-625983Y-467833D01*
X-627033Y-468334D01*
X-629833D01*
G01X-620333Y-472500D02*
Y-462500D01*
X-617417D01*
X-616483Y-463000D01*
X-615900Y-463667D01*
X-615667Y-465000D01*
X-615900Y-466333D01*
X-616600Y-467167D01*
X-617417Y-467667D01*
X-620333D01*
G01X-617417D02*
X-615667Y-472500D01*
G01X-610017Y-469167D02*
X-606983D01*
G01X-599000Y-472500D02*
Y-462500D01*
X-600400Y-464500D01*
G01Y-472500D02*
X-597600D01*
G01X-588100D02*
Y-462500D01*
X-592417Y-469667D01*
X-586583D01*
G54D21*
X-1356889Y-145000D03*
X-1051613D03*
X-486810D03*
X-181534D03*
G54D12*
X-1656000Y-135000D03*
X-1615984Y-173071D03*
Y-178583D03*
Y-167559D03*
X-1608110Y-172677D03*
Y-178189D03*
Y-167165D03*
X-1615984Y-162047D03*
Y-151024D03*
Y-156535D03*
X-1608110Y-161654D03*
Y-150630D03*
Y-156142D03*
X-1615984Y-134488D03*
Y-140000D03*
Y-145512D03*
X-1608110Y-134094D03*
Y-139606D03*
Y-145118D03*
X-1615984Y-128976D03*
Y-123465D03*
Y-117953D03*
X-1608110Y-128583D03*
Y-123071D03*
Y-117559D03*
X-1615984Y-112441D03*
Y-106929D03*
Y-101417D03*
X-1608110Y-112047D03*
Y-106535D03*
Y-101024D03*
X-1615984Y-95906D03*
X-1600236Y-167559D03*
X-1592362Y-167165D03*
X-1600236Y-173071D03*
X-1592362Y-172677D03*
X-1600236Y-178583D03*
X-1592362Y-178189D03*
X-1600236Y-151024D03*
X-1592362Y-150630D03*
X-1600236Y-156535D03*
X-1592362Y-156142D03*
X-1600236Y-162047D03*
X-1592362Y-161654D03*
X-1600236Y-134488D03*
X-1592362Y-134094D03*
X-1600236Y-140000D03*
X-1592362Y-139606D03*
X-1600236Y-145512D03*
X-1592362Y-145118D03*
X-1600236Y-128976D03*
Y-117953D03*
Y-123465D03*
X-1592362Y-128583D03*
Y-117559D03*
Y-123071D03*
X-1600236Y-101417D03*
Y-106929D03*
Y-112441D03*
X-1592362Y-101024D03*
Y-106535D03*
Y-112047D03*
X-1600236Y-95906D03*
X-1584488Y-167559D03*
X-1576614Y-167165D03*
X-1584488Y-173071D03*
X-1576614Y-172677D03*
X-1584488Y-178583D03*
X-1576614Y-178189D03*
X-1584488Y-151024D03*
X-1576614Y-150630D03*
X-1584488Y-156535D03*
X-1576614Y-156142D03*
X-1584488Y-162047D03*
X-1576614Y-161654D03*
X-1584488Y-134488D03*
X-1576614Y-134094D03*
X-1584488Y-140000D03*
X-1576614Y-139606D03*
X-1584488Y-145512D03*
X-1576614Y-145118D03*
X-1584488Y-128976D03*
X-1576614Y-128583D03*
X-1584488Y-117953D03*
X-1576614Y-117559D03*
X-1584488Y-123465D03*
X-1576614Y-123071D03*
X-1584488Y-101417D03*
X-1576614Y-101024D03*
X-1584488Y-106929D03*
X-1576614Y-106535D03*
X-1584488Y-112441D03*
X-1576614Y-112047D03*
X-1584488Y-95906D03*
X-1568740Y-167559D03*
X-1560866Y-167165D03*
X-1568740Y-173071D03*
X-1560866Y-172677D03*
X-1568740Y-178583D03*
X-1560866Y-178189D03*
X-1568740Y-151024D03*
X-1560866Y-150630D03*
X-1568740Y-156535D03*
X-1560866Y-156142D03*
X-1568740Y-162047D03*
X-1560866Y-161654D03*
X-1568740Y-134488D03*
X-1560866Y-134094D03*
X-1568740Y-140000D03*
X-1560866Y-139606D03*
X-1568740Y-145512D03*
X-1560866Y-145118D03*
X-1568740Y-128976D03*
Y-117953D03*
Y-123465D03*
X-1560866Y-128583D03*
Y-117559D03*
Y-123071D03*
X-1568740Y-101417D03*
Y-106929D03*
Y-112441D03*
X-1560866Y-101024D03*
Y-106535D03*
Y-112047D03*
X-1568740Y-95906D03*
X-1552992Y-167559D03*
X-1545118Y-167165D03*
X-1552992Y-173071D03*
X-1545118Y-172677D03*
X-1552992Y-178583D03*
Y-151024D03*
X-1545118Y-150630D03*
X-1552992Y-156535D03*
X-1545118Y-156142D03*
X-1552992Y-162047D03*
X-1545118Y-161654D03*
X-1552992Y-134488D03*
X-1545118Y-134094D03*
X-1552992Y-140000D03*
X-1545118Y-139606D03*
X-1552992Y-145512D03*
X-1545118Y-145118D03*
X-1552992Y-128976D03*
Y-117953D03*
Y-123465D03*
X-1545118Y-128583D03*
Y-117559D03*
Y-123071D03*
X-1552992Y-101417D03*
Y-106929D03*
Y-112441D03*
X-1545118Y-101024D03*
Y-106535D03*
Y-112047D03*
X-1552992Y-95906D03*
X-1535063Y-22160D03*
X-1535000Y-32500D03*
X-1524359Y-125359D03*
X-1497043Y-169390D03*
X-1486693Y-76890D03*
X-1475063Y-22160D03*
X-1450000Y-112500D03*
X-1437500Y-175000D03*
X-1421250Y-81250D03*
X-1387500Y-150000D03*
X-1371250Y-112500D03*
X-1368750Y-82500D03*
X-1324840Y-82120D03*
X-1335400Y-75000D03*
X-1324500Y-26959D03*
X-1311200Y-30200D03*
X-1298780Y-52200D03*
X-1298000Y-41200D03*
X-1298700Y-35700D03*
X-1255315Y-157350D03*
X-1232500Y-45000D03*
X-1217520Y-157350D03*
X-1197008Y-167953D03*
X-1189134Y-167559D03*
X-1197008Y-173465D03*
X-1189134Y-173071D03*
X-1197008Y-178976D03*
X-1189134Y-178583D03*
X-1197008Y-151417D03*
X-1189134Y-151024D03*
X-1197008Y-156929D03*
X-1189134Y-156535D03*
X-1197008Y-162441D03*
X-1189134Y-162047D03*
X-1197008Y-134882D03*
X-1189134Y-134488D03*
X-1197008Y-140394D03*
X-1189134Y-140000D03*
X-1197008Y-145906D03*
X-1189134Y-145512D03*
X-1197008Y-129370D03*
X-1191000Y-46500D03*
X-1181260Y-167953D03*
X-1173386Y-167559D03*
X-1181260Y-173465D03*
X-1173386Y-173071D03*
X-1181260Y-178976D03*
X-1173386Y-178583D03*
X-1181260Y-151417D03*
X-1173386Y-151024D03*
X-1181260Y-156929D03*
X-1173386Y-156535D03*
X-1181260Y-162441D03*
X-1173386Y-162047D03*
X-1181260Y-134882D03*
X-1173386Y-134488D03*
X-1181260Y-140394D03*
X-1173386Y-140000D03*
X-1181260Y-145906D03*
X-1173386Y-145512D03*
X-1181260Y-129370D03*
X-1178950Y-23250D03*
X-1165512Y-167953D03*
X-1157638Y-167559D03*
X-1165512Y-173465D03*
X-1157638Y-173071D03*
X-1165512Y-178976D03*
X-1157638Y-178583D03*
X-1165512Y-151417D03*
X-1157638Y-151024D03*
X-1165512Y-156929D03*
X-1157638Y-156535D03*
X-1165512Y-162441D03*
X-1157638Y-162047D03*
X-1165512Y-134882D03*
X-1157638Y-134488D03*
X-1165512Y-140394D03*
X-1157638Y-140000D03*
X-1165512Y-145906D03*
X-1157638Y-145512D03*
X-1165512Y-129370D03*
X-1160150Y-26750D03*
X-1158700Y-16250D03*
X-1151500Y-15000D03*
X-1159700Y-5750D03*
X-1124700Y-180000D03*
X-1124900Y-170650D03*
X-1121870Y-104330D03*
X-1128810Y-104171D03*
X-1115490Y-104240D03*
X-1095600Y-179600D03*
X-1096278Y-170650D03*
X-1100000Y-15000D03*
X-1056900Y-56300D03*
X-1051200Y-44100D03*
X-1054900Y-29800D03*
X-1047289Y-26300D03*
X-1054600Y-5100D03*
X-1047300Y-2700D03*
X-1014488Y-167953D03*
Y-173465D03*
Y-178976D03*
Y-151417D03*
Y-156929D03*
Y-162441D03*
Y-134882D03*
Y-140394D03*
Y-145906D03*
Y-129370D03*
X-1012500Y-7500D03*
X-1006614Y-167559D03*
X-998740Y-167953D03*
X-1006614Y-173071D03*
X-998740Y-173465D03*
X-1006614Y-178583D03*
X-998740Y-178976D03*
X-1006614Y-151024D03*
X-998740Y-151417D03*
X-1006614Y-156535D03*
X-998740Y-156929D03*
X-1006614Y-162047D03*
X-998740Y-162441D03*
X-1006614Y-134488D03*
X-998740Y-134882D03*
X-1006614Y-140000D03*
X-998740Y-140394D03*
X-1006614Y-145512D03*
X-998740Y-145906D03*
Y-129370D03*
X-990866Y-167559D03*
X-982992Y-167953D03*
X-990866Y-173071D03*
X-982992Y-173465D03*
X-990866Y-178583D03*
X-982992Y-178976D03*
X-990866Y-151024D03*
X-982992Y-151417D03*
X-990866Y-156535D03*
X-982992Y-156929D03*
X-990866Y-162047D03*
X-982992Y-162441D03*
X-990866Y-134488D03*
X-982992Y-134882D03*
X-990866Y-140000D03*
X-982992Y-140394D03*
X-990866Y-145512D03*
X-982992Y-145906D03*
Y-129370D03*
X-975118Y-167559D03*
Y-173071D03*
Y-178583D03*
Y-151024D03*
Y-156535D03*
Y-162047D03*
Y-134488D03*
Y-140000D03*
Y-145512D03*
X-970000Y-7500D03*
X-932500D03*
X-860000Y-45000D03*
X-745906Y-173071D03*
Y-178583D03*
Y-167559D03*
Y-162047D03*
Y-151024D03*
Y-156535D03*
Y-134488D03*
Y-140000D03*
Y-145512D03*
Y-128976D03*
Y-123465D03*
Y-117953D03*
Y-112441D03*
Y-106929D03*
Y-101417D03*
Y-95906D03*
X-738032Y-172677D03*
Y-178189D03*
Y-167165D03*
X-730157Y-167559D03*
Y-173071D03*
Y-178583D03*
X-738032Y-161654D03*
Y-150630D03*
Y-156142D03*
X-730157Y-151024D03*
Y-156535D03*
Y-162047D03*
X-738032Y-134094D03*
Y-139606D03*
Y-145118D03*
X-730157Y-134488D03*
Y-140000D03*
Y-145512D03*
Y-128976D03*
X-738032Y-128583D03*
X-730157Y-117953D03*
Y-123465D03*
X-738032Y-123071D03*
Y-117559D03*
X-730157Y-101417D03*
Y-106929D03*
Y-112441D03*
X-738032Y-112047D03*
Y-106535D03*
Y-101024D03*
X-730157Y-95906D03*
X-722283Y-167165D03*
X-714409Y-167559D03*
X-722283Y-172677D03*
X-714409Y-173071D03*
X-722283Y-178189D03*
X-714409Y-178583D03*
X-722283Y-150630D03*
X-714409Y-151024D03*
X-722283Y-156142D03*
X-714409Y-156535D03*
X-722283Y-161654D03*
X-714409Y-162047D03*
X-722283Y-134094D03*
X-714409Y-134488D03*
X-722283Y-139606D03*
X-714409Y-140000D03*
X-722283Y-145118D03*
X-714409Y-145512D03*
X-722283Y-128583D03*
Y-117559D03*
Y-123071D03*
X-714409Y-128976D03*
Y-117953D03*
Y-123465D03*
X-722283Y-101024D03*
Y-106535D03*
Y-112047D03*
X-714409Y-101417D03*
Y-106929D03*
Y-112441D03*
Y-95906D03*
X-706535Y-167165D03*
X-698661Y-167559D03*
X-706535Y-172677D03*
X-698661Y-173071D03*
X-706535Y-178189D03*
X-698661Y-178583D03*
X-706535Y-150630D03*
X-698661Y-151024D03*
X-706535Y-156142D03*
X-698661Y-156535D03*
X-706535Y-161654D03*
X-698661Y-162047D03*
X-706535Y-134094D03*
X-698661Y-134488D03*
X-706535Y-139606D03*
X-698661Y-140000D03*
X-706535Y-145118D03*
X-698661Y-145512D03*
X-706535Y-128583D03*
Y-117559D03*
Y-123071D03*
X-698661Y-128976D03*
Y-117953D03*
Y-123465D03*
X-706535Y-101024D03*
Y-106535D03*
Y-112047D03*
X-698661Y-101417D03*
Y-106929D03*
Y-112441D03*
Y-95906D03*
X-690787Y-167165D03*
X-682913Y-167559D03*
X-690787Y-172677D03*
X-682913Y-173071D03*
X-690787Y-178189D03*
X-682913Y-178583D03*
X-690787Y-150630D03*
X-682913Y-151024D03*
X-690787Y-156142D03*
X-682913Y-156535D03*
X-690787Y-161654D03*
X-682913Y-162047D03*
X-690787Y-134094D03*
X-682913Y-134488D03*
X-690787Y-139606D03*
X-682913Y-140000D03*
X-690787Y-145118D03*
X-682913Y-145512D03*
X-690787Y-128583D03*
X-682913Y-128976D03*
X-690787Y-117559D03*
X-682913Y-117953D03*
X-690787Y-123071D03*
X-682913Y-123465D03*
X-690787Y-101024D03*
X-682913Y-101417D03*
X-690787Y-106535D03*
X-682913Y-106929D03*
X-690787Y-112047D03*
X-682913Y-112441D03*
Y-95906D03*
X-685000Y-45000D03*
X-675039Y-167165D03*
Y-172677D03*
Y-150630D03*
Y-156142D03*
Y-161654D03*
Y-134094D03*
Y-139606D03*
Y-145118D03*
Y-128583D03*
Y-117559D03*
Y-123071D03*
Y-101024D03*
Y-106535D03*
Y-112047D03*
X-626964Y-169390D03*
X-621614Y-76890D03*
X-577500Y-115000D03*
X-502500Y-12500D03*
X-444440Y-80710D03*
X-442800Y-46600D03*
X-430180Y-52100D03*
X-429400Y-41100D03*
X-430400Y-35600D03*
X-424500Y-26500D03*
X-385237Y-157350D03*
X-386500Y-56500D03*
Y-5500D03*
X-374000Y-31500D03*
X-347441Y-157350D03*
X-348000Y-31500D03*
X-342400Y-87500D03*
X-326929Y-167953D03*
X-319055Y-167559D03*
X-326929Y-173465D03*
X-319055Y-173071D03*
X-326929Y-178976D03*
X-319055Y-178583D03*
X-326929Y-151417D03*
X-319055Y-151024D03*
X-326929Y-156929D03*
X-319055Y-156535D03*
X-326929Y-162441D03*
X-319055Y-162047D03*
X-326929Y-134882D03*
X-319055Y-134488D03*
X-326929Y-140394D03*
X-319055Y-140000D03*
X-326929Y-145906D03*
X-319055Y-145512D03*
X-326929Y-129370D03*
X-321500Y-47500D03*
X-311181Y-167953D03*
X-303307Y-167559D03*
X-311181Y-173465D03*
X-303307Y-173071D03*
X-311181Y-178976D03*
X-303307Y-178583D03*
X-311181Y-151417D03*
X-303307Y-151024D03*
X-311181Y-156929D03*
X-303307Y-156535D03*
X-311181Y-162441D03*
X-303307Y-162047D03*
X-311181Y-134882D03*
X-303307Y-134488D03*
X-311181Y-140394D03*
X-303307Y-140000D03*
X-311181Y-145906D03*
X-303307Y-145512D03*
X-311181Y-129370D03*
X-302500Y-15200D03*
X-295433Y-167953D03*
X-287559Y-167559D03*
X-295433Y-173465D03*
X-287559Y-173071D03*
X-295433Y-178976D03*
X-287559Y-178583D03*
X-295433Y-151417D03*
X-287559Y-151024D03*
X-295433Y-156929D03*
X-287559Y-156535D03*
X-295433Y-162441D03*
X-287559Y-162047D03*
X-295433Y-134882D03*
X-287559Y-134488D03*
X-295433Y-140394D03*
X-287559Y-140000D03*
X-295433Y-145906D03*
X-287559Y-145512D03*
X-295433Y-129370D03*
X-289500Y-32500D03*
X-290800Y-26000D03*
X-254800Y-180000D03*
X-258732Y-104171D03*
X-255500Y-25500D03*
X-268000Y-500D03*
X-245411Y-104240D03*
X-251792Y-104330D03*
X-225400Y-179800D03*
X-226200Y-170650D03*
X-232874Y-104200D03*
X-230500Y-500D03*
X-191000Y-56400D03*
X-190300Y-28900D03*
Y-4200D03*
X-179800Y-43500D03*
X-176350Y-27200D03*
X-175100Y-1800D03*
X-144409Y-167953D03*
Y-173465D03*
Y-178976D03*
Y-151417D03*
Y-156929D03*
Y-162441D03*
Y-134882D03*
Y-140394D03*
Y-145906D03*
Y-129370D03*
X-136535Y-167559D03*
X-128661Y-167953D03*
X-136535Y-173071D03*
X-128661Y-173465D03*
X-136535Y-178583D03*
X-128661Y-178976D03*
X-136535Y-151024D03*
X-128661Y-151417D03*
X-136535Y-156535D03*
X-128661Y-156929D03*
X-136535Y-162047D03*
X-128661Y-162441D03*
X-136535Y-134488D03*
X-128661Y-134882D03*
X-136535Y-140000D03*
X-128661Y-140394D03*
X-136535Y-145512D03*
X-128661Y-145906D03*
Y-129370D03*
X-120787Y-167559D03*
X-112913Y-167953D03*
X-120787Y-173071D03*
X-112913Y-173465D03*
X-120787Y-178583D03*
X-112913Y-178976D03*
X-120787Y-151024D03*
X-112913Y-151417D03*
X-120787Y-156535D03*
X-112913Y-156929D03*
X-120787Y-162047D03*
X-112913Y-162441D03*
X-120787Y-134488D03*
X-112913Y-134882D03*
X-120787Y-140000D03*
X-112913Y-140394D03*
X-120787Y-145512D03*
X-112913Y-145906D03*
Y-129370D03*
X-126500Y-8500D03*
X-105039Y-167559D03*
Y-173071D03*
Y-178583D03*
Y-151024D03*
Y-156535D03*
Y-162047D03*
Y-134488D03*
Y-140000D03*
Y-145512D03*
X-59500Y-108500D03*
Y-58500D03*
Y-21000D03*
X-34500Y-83500D03*
X-9500Y-58500D03*
X3000Y-96000D03*
G54D31*
G01X-1174900Y-473500D02*
X-1171300Y-466100D01*
X-1171800Y-465700D01*
X-1175900Y-473200D01*
X-1176200Y-471200D01*
X-1172500Y-465400D01*
X-1175700Y-471300D01*
X-1176500Y-469800D01*
X-1172900Y-464900D01*
X-1173600Y-451800D01*
X-1173700Y-449900D01*
X-1182100D01*
X-1187400Y-473000D01*
X-1182400D01*
X-1177800Y-456000D01*
X-1177000Y-455900D01*
X-1176100Y-468500D01*
X-1173700Y-464500D01*
X-1174600Y-450800D01*
X-1181500Y-450900D01*
X-1186400Y-472100D01*
X-1183100D01*
X-1178300Y-454800D01*
X-1176600Y-455000D01*
X-1175500Y-466300D01*
X-1174600Y-464300D01*
X-1175400Y-451700D01*
X-1181000Y-451800D01*
X-1185300Y-471300D01*
X-1183800Y-471400D01*
X-1179000Y-454300D01*
X-1176200D01*
X-1175200Y-462200D01*
X-1176200Y-452500D01*
X-1180500Y-452800D01*
X-1184300Y-470600D01*
X-1179700Y-453400D01*
X-1176800D01*
G01X-1182820Y-448900D02*
X-1188360Y-473900D01*
X-1181580D01*
X-1177300Y-456700D01*
X-1176920Y-473900D01*
X-1172260D01*
X-1163400Y-456920D01*
X-1167240Y-473900D01*
X-1160380D01*
X-1154840Y-448900D01*
X-1164540D01*
X-1172540Y-464820D01*
X-1172880Y-448900D01*
X-1182820D01*
G01X-1155800Y-449500D02*
X-1161100Y-472900D01*
X-1166100Y-473000D01*
X-1166000Y-471900D01*
X-1161800Y-472100D01*
X-1161300Y-471000D01*
X-1165900Y-471100D01*
X-1165700Y-470000D01*
X-1161300D01*
X-1160800Y-469200D01*
X-1165300Y-469100D01*
X-1165200Y-468100D01*
X-1160700D01*
X-1160400Y-467100D01*
X-1165100Y-467200D01*
X-1164900Y-466300D01*
X-1160300Y-466200D01*
X-1160000Y-465200D01*
X-1164700Y-465300D01*
X-1164400Y-464200D01*
X-1159700Y-464300D01*
X-1159300Y-463100D01*
X-1164700Y-463500D01*
X-1164000Y-462500D01*
X-1159500Y-462600D01*
X-1159000Y-461700D01*
X-1163900D01*
X-1163600Y-460600D01*
X-1159100Y-460800D01*
X-1158800Y-459900D01*
X-1163200D01*
X-1163100Y-459200D01*
X-1158800D01*
X-1158300Y-458500D01*
X-1163000Y-458400D01*
X-1162900Y-457800D01*
X-1158400Y-457900D01*
X-1158200Y-457200D01*
X-1162500Y-457000D01*
X-1163100Y-456500D01*
X-1157800D01*
X-1157500Y-455500D01*
X-1156600Y-449800D01*
X-1164000D01*
X-1164500Y-450700D01*
X-1157600D01*
X-1157800Y-451700D01*
X-1165000Y-451600D01*
X-1165400Y-452400D01*
X-1157900Y-452500D01*
X-1157800Y-453500D01*
X-1165900Y-453200D01*
X-1166200Y-453900D01*
X-1158000Y-454300D01*
X-1158300Y-455300D01*
X-1166600Y-454800D01*
X-1158900Y-455900D01*
X-1167000Y-455600D01*
X-1163500Y-456400D01*
X-1167300Y-456300D01*
X-1171700Y-465200D01*
X-1169200Y-466400D01*
X-1164500Y-457200D01*
X-1166900Y-457100D01*
X-1170600Y-465200D01*
X-1169500Y-465500D01*
X-1166000Y-457800D01*
G01X-1170300Y-466300D02*
X-1174000Y-473600D01*
G01X-1169500Y-466900D02*
X-1172800Y-473000D01*
G01X-1152800Y-456400D02*
X-1156600Y-473100D01*
X-1152200Y-473000D01*
X-1148300Y-456600D01*
X-1149500D01*
X-1152900Y-472000D01*
X-1155600Y-472300D01*
X-1152100Y-456500D01*
X-1150400Y-456400D01*
X-1153600Y-471200D01*
X-1154500Y-471400D01*
X-1151400Y-457200D01*
G01X-1153420Y-455700D02*
X-1157540Y-473900D01*
X-1151380D01*
X-1147440Y-455700D01*
X-1153420D01*
G01X-1151600Y-450100D02*
X-1146700Y-450000D01*
X-1147000Y-451000D01*
X-1151700D01*
G01X-1152020Y-448900D02*
X-1152660Y-451900D01*
X-1146380D01*
X-1145740Y-448900D01*
X-1152020D01*
G01X-1129400Y-468900D02*
X-1131800Y-471900D01*
X-1136500Y-473700D01*
X-1142100Y-473600D01*
X-1144600Y-472300D01*
X-1145800Y-471000D01*
X-1146400Y-469500D01*
X-1146700Y-467600D01*
X-1146500Y-464600D01*
X-1145400Y-461200D01*
X-1143500Y-459100D01*
X-1140200Y-456900D01*
X-1136100Y-456200D01*
X-1132300Y-456400D01*
X-1129400Y-457900D01*
X-1127500Y-460900D01*
X-1132500Y-461000D01*
X-1133400Y-459200D01*
X-1135100Y-458100D01*
X-1136800Y-458000D01*
X-1138600Y-458900D01*
X-1140300Y-460700D01*
X-1141800Y-463600D01*
X-1142400Y-466600D01*
X-1141500Y-470400D01*
X-1140200Y-471500D01*
X-1138300Y-471600D01*
X-1136300Y-471400D01*
X-1134500Y-469100D01*
X-1130300Y-469000D01*
X-1132500Y-471200D01*
X-1134900Y-472000D01*
X-1137200Y-472800D01*
X-1142300Y-472700D01*
X-1144900Y-470600D01*
X-1145800Y-467400D01*
X-1145500Y-465100D01*
X-1144700Y-462000D01*
X-1143300Y-460200D01*
X-1139800Y-457700D01*
X-1135400Y-457000D01*
X-1131300Y-457600D01*
X-1128800Y-460100D01*
X-1132100D01*
X-1134300Y-457900D01*
X-1130100Y-458800D01*
X-1129500Y-459400D01*
X-1132600Y-459000D01*
G01X-1133300Y-461900D02*
Y-461420D01*
X-1133640Y-460240D01*
X-1134300Y-459200D01*
X-1135200Y-458900D01*
X-1136580D01*
X-1138060Y-459820D01*
X-1139360Y-461000D01*
X-1140240Y-462220D01*
X-1140880Y-463920D01*
X-1141300Y-465380D01*
X-1141500Y-467060D01*
Y-468020D01*
X-1141020Y-469220D01*
X-1139780Y-470700D01*
X-1137160D01*
X-1135840Y-469500D01*
X-1134980Y-468200D01*
X-1134940Y-468100D01*
X-1128180D01*
X-1128240Y-468240D01*
X-1128840Y-469340D01*
X-1129020Y-469800D01*
X-1129740Y-470700D01*
X-1130500Y-471460D01*
X-1131660Y-472420D01*
X-1132820Y-473200D01*
X-1133740Y-473740D01*
X-1136380Y-474500D01*
X-1141640D01*
X-1142540Y-474320D01*
X-1144220Y-473760D01*
X-1144900Y-473240D01*
X-1146240Y-471900D01*
X-1146780Y-471180D01*
X-1146940Y-470880D01*
X-1147320Y-469660D01*
X-1147500Y-468640D01*
Y-464780D01*
X-1146940Y-462540D01*
X-1146380Y-461580D01*
X-1145980Y-460780D01*
X-1145420Y-459880D01*
X-1143700Y-458140D01*
X-1142740Y-457380D01*
X-1142000Y-456820D01*
X-1140240Y-456040D01*
X-1139500Y-455660D01*
X-1138800Y-455480D01*
X-1137260Y-455300D01*
X-1134320D01*
X-1132020Y-455500D01*
X-1130940Y-455860D01*
X-1130580Y-456020D01*
X-1129260Y-456780D01*
X-1128940Y-457100D01*
X-1127820Y-458420D01*
X-1127060Y-460300D01*
X-1126900Y-460800D01*
Y-461900D01*
X-1133300D01*
G01X-1137900Y-458000D02*
X-1140300Y-459100D01*
X-1142500Y-460900D01*
X-1143900Y-462600D01*
X-1144800Y-467600D01*
X-1144200Y-470000D01*
X-1141000Y-472300D01*
X-1136400Y-472200D01*
X-1131600Y-469600D01*
X-1135400Y-470400D01*
X-1141100Y-471400D01*
X-1142100Y-470700D01*
X-1142700Y-469000D01*
X-1143100Y-467100D01*
X-1142700Y-464100D01*
X-1140500Y-459900D01*
X-1143400Y-463700D01*
X-1143600Y-465700D01*
X-1143900Y-467700D01*
X-1143000Y-469900D01*
G01X-1113500Y-459200D02*
X-1123500Y-459300D01*
X-1123700Y-460100D01*
X-1114300Y-460000D01*
X-1116500Y-460800D01*
X-1124200Y-461000D01*
X-1124400Y-461900D01*
X-1117600Y-461800D01*
X-1118800Y-462800D01*
X-1124500Y-462700D01*
X-1124600Y-463600D01*
X-1119300Y-463700D01*
X-1120100Y-464800D01*
X-1125000Y-464600D01*
Y-465500D01*
X-1120600Y-465700D01*
X-1120800Y-466700D01*
X-1125300Y-466500D01*
X-1125500Y-467400D01*
X-1121000Y-467600D01*
X-1121200Y-468700D01*
X-1125600Y-468400D01*
X-1125900Y-469100D01*
X-1121500Y-469500D01*
X-1121700Y-470700D01*
X-1126100Y-470000D01*
X-1126200Y-470700D01*
X-1121900Y-471200D01*
X-1122100Y-472000D01*
X-1126300Y-471700D01*
X-1126700Y-472300D01*
X-1122100Y-472700D01*
X-1122200Y-473100D01*
X-1126800Y-473200D01*
G01X-1114060Y-460760D02*
X-1114840Y-460920D01*
X-1115740Y-461140D01*
X-1116880Y-461820D01*
X-1117700Y-462640D01*
X-1118620Y-463340D01*
X-1118840Y-464020D01*
X-1119440Y-464820D01*
X-1119660Y-465480D01*
X-1120060Y-466280D01*
X-1120280Y-466960D01*
X-1120480Y-468360D01*
X-1120680Y-468940D01*
X-1120880Y-469940D01*
X-1121080Y-470540D01*
X-1121700Y-472980D01*
X-1121820Y-473900D01*
X-1127640D01*
X-1126920Y-471060D01*
X-1126720Y-470440D01*
X-1126500Y-468800D01*
X-1126320Y-467860D01*
X-1126120Y-467260D01*
X-1125920Y-466260D01*
X-1125720Y-465660D01*
X-1125300Y-464000D01*
X-1125120Y-462220D01*
X-1124920Y-461660D01*
X-1124720Y-460660D01*
X-1124520Y-460060D01*
X-1123720Y-456800D01*
X-1123580Y-455700D01*
X-1117880D01*
X-1118100Y-456160D01*
Y-458740D01*
X-1116500Y-457160D01*
X-1115780Y-456620D01*
X-1114680Y-456060D01*
X-1113560Y-455680D01*
X-1112460Y-455500D01*
X-1111720D01*
X-1112460Y-458440D01*
X-1114060Y-460760D01*
G01X-1123100Y-456500D02*
X-1118900Y-456600D01*
X-1118800Y-457600D01*
X-1123100Y-457500D01*
X-1123300Y-458500D01*
X-1113100Y-458400D01*
X-1112600Y-456400D01*
X-1116100Y-457600D01*
X-1113500D01*
G01X-1105100Y-471100D02*
X-1104060D01*
X-1103780Y-470820D01*
X-1103200Y-470640D01*
X-1102080Y-469740D01*
X-1100800Y-468240D01*
X-1100380Y-467400D01*
X-1100180Y-467100D01*
X-1099960Y-466660D01*
X-1099540Y-465720D01*
X-1099320Y-465060D01*
X-1099100Y-464180D01*
Y-461220D01*
X-1099360Y-460200D01*
X-1099660Y-459900D01*
X-1100700Y-458640D01*
X-1101220Y-458300D01*
X-1103340D01*
X-1103700Y-458640D01*
X-1105300Y-459840D01*
X-1105760Y-460320D01*
X-1106180Y-460940D01*
X-1107060Y-462020D01*
X-1107260Y-462880D01*
X-1107660Y-463660D01*
X-1108100Y-465000D01*
Y-468640D01*
X-1107620Y-469600D01*
X-1107140Y-470340D01*
X-1105980Y-471100D01*
X-1105100D01*
G01X-1112540Y-460460D02*
X-1110680Y-458140D01*
X-1109940Y-457580D01*
X-1109000Y-456840D01*
X-1108480Y-456660D01*
X-1107940Y-456400D01*
X-1107740Y-456200D01*
X-1107480Y-456060D01*
X-1106880Y-455860D01*
X-1106480Y-455660D01*
X-1105960Y-455480D01*
X-1104600Y-455300D01*
X-1103440Y-455100D01*
X-1100940D01*
X-1098240Y-455480D01*
X-1097720Y-455660D01*
X-1097020Y-456020D01*
X-1096180Y-456640D01*
X-1095620Y-456820D01*
X-1095540Y-456900D01*
X-1094200Y-458440D01*
X-1093660Y-459520D01*
X-1093460Y-460100D01*
X-1093100Y-461020D01*
Y-464400D01*
X-1093420Y-465360D01*
X-1094300Y-465520D01*
X-1094720Y-465740D01*
X-1095320Y-465940D01*
X-1096120Y-466340D01*
X-1096720Y-466540D01*
X-1097100Y-466720D01*
X-1098100Y-466920D01*
X-1098520Y-467140D01*
X-1099160Y-467360D01*
X-1101180Y-468700D01*
X-1094660D01*
X-1095220Y-469800D01*
X-1095560Y-470320D01*
X-1097480Y-472220D01*
X-1099940Y-473740D01*
X-1102580Y-474500D01*
X-1108800D01*
X-1109300Y-474340D01*
X-1111220Y-473560D01*
X-1111720Y-473240D01*
X-1113240Y-471720D01*
X-1113560Y-471240D01*
X-1113760Y-470660D01*
X-1114140Y-469980D01*
X-1114320Y-469120D01*
X-1114500Y-468680D01*
Y-464980D01*
X-1114320Y-464260D01*
X-1114140Y-463720D01*
X-1113940Y-463320D01*
X-1113720Y-462660D01*
X-1113560Y-462000D01*
X-1111880Y-460320D01*
X-1112540Y-460460D01*
G01X-1099300Y-466400D02*
X-1093800Y-464400D01*
X-1093900Y-461100D01*
X-1094800Y-459000D01*
X-1096800Y-457300D01*
X-1100000Y-456100D01*
X-1102800Y-455900D01*
X-1106300Y-456300D01*
X-1109600Y-458100D01*
X-1111400Y-460500D01*
X-1112900Y-462600D01*
X-1113600Y-465600D01*
X-1113500Y-469100D01*
X-1112100Y-471900D01*
X-1109600Y-473300D01*
X-1105700Y-473800D01*
X-1101000Y-473400D01*
X-1098200Y-471800D01*
X-1096600Y-470100D01*
X-1096000Y-469500D01*
X-1100800Y-469700D01*
X-1102300Y-471100D01*
X-1097900Y-470400D01*
X-1100300Y-471800D01*
X-1103200Y-471400D01*
X-1100600Y-472600D01*
X-1103000D01*
X-1103700Y-471900D01*
X-1103400Y-473000D01*
X-1104600Y-471900D01*
X-1106200D01*
X-1104100Y-473100D01*
X-1107200Y-472700D01*
X-1110100Y-472100D01*
X-1111500Y-470900D01*
X-1112600Y-468600D01*
X-1112700Y-466000D01*
X-1112400Y-463700D01*
X-1111400Y-461600D01*
X-1109600Y-459500D01*
X-1108100Y-458200D01*
X-1105900Y-457200D01*
X-1102200Y-456700D01*
X-1099600Y-457300D01*
X-1097000Y-458400D01*
X-1095500Y-459500D01*
X-1094600Y-461900D01*
X-1094500Y-463900D01*
X-1098800Y-465200D01*
X-1098600Y-464000D01*
X-1095100Y-463100D01*
X-1095300Y-462000D01*
X-1098500Y-463000D01*
X-1098600Y-461700D01*
X-1095600Y-461300D01*
X-1095900Y-460200D01*
X-1098400Y-460700D01*
X-1098900Y-459900D01*
X-1096600Y-459400D01*
X-1097100Y-458900D01*
X-1099400Y-459000D01*
X-1098800Y-458500D01*
X-1100600Y-458000D01*
X-1102400Y-457400D01*
X-1104200Y-457500D01*
X-1106200Y-458100D01*
X-1107900Y-459000D01*
X-1110500Y-462200D01*
X-1111800Y-464800D01*
Y-467700D01*
X-1110700Y-470300D01*
X-1108700Y-472000D01*
X-1106600Y-471900D01*
X-1107900Y-470300D01*
X-1108900Y-468700D01*
Y-465500D01*
X-1107900Y-462300D01*
X-1106500Y-459900D01*
X-1104100Y-458200D01*
X-1108000Y-460000D01*
X-1108100Y-461500D01*
X-1108700Y-461200D01*
X-1110300Y-463600D01*
X-1111000Y-466000D01*
X-1110700Y-468100D01*
X-1109500Y-470600D01*
X-1107700Y-471400D01*
X-1109300Y-469100D01*
X-1109800Y-467600D01*
X-1108600Y-462200D01*
X-1110400Y-466800D01*
G01X-1113600Y-460900D02*
X-1112100Y-459000D01*
G01X-1093100Y-469400D02*
X-1087900Y-469700D01*
X-1086500Y-471400D01*
X-1083400Y-472300D01*
X-1081000Y-472000D01*
X-1079300Y-470600D01*
X-1079000Y-468900D01*
X-1079500Y-467700D01*
X-1080300Y-466600D01*
X-1081800Y-466000D01*
X-1083300Y-465500D01*
X-1085300Y-465000D01*
X-1087900Y-464000D01*
X-1089100Y-463200D01*
X-1089800Y-461000D01*
X-1089500Y-459000D01*
X-1088600Y-457700D01*
X-1086500Y-456700D01*
X-1084600Y-456100D01*
X-1081900Y-455900D01*
X-1079900Y-455800D01*
X-1076900Y-456300D01*
X-1075000Y-457000D01*
X-1073700Y-458000D01*
X-1073300Y-459400D01*
X-1077600Y-459500D01*
X-1078100Y-458800D01*
X-1074300Y-458500D01*
X-1074600Y-457800D01*
X-1078200Y-458200D01*
X-1076000Y-457400D01*
X-1079100Y-457700D01*
X-1077100Y-456900D01*
X-1080100Y-457300D01*
X-1079200Y-456600D01*
X-1083100Y-456800D01*
X-1080600Y-457300D01*
X-1083400Y-457700D01*
X-1083600Y-457000D01*
X-1087900Y-458400D01*
X-1084000Y-458100D01*
X-1088600Y-459100D01*
X-1088800Y-461500D01*
X-1087700Y-463600D01*
X-1084400Y-464300D01*
X-1081200Y-465400D01*
X-1078800Y-467300D01*
X-1078300Y-470500D01*
X-1079900Y-472600D01*
X-1083500Y-473300D01*
X-1085600Y-472600D01*
X-1088800Y-470500D01*
X-1092600Y-470200D01*
X-1092100Y-471800D01*
X-1091700Y-471300D01*
X-1089300Y-471500D01*
X-1091300Y-472300D01*
X-1088700Y-471600D01*
X-1084000Y-473500D01*
X-1089100D01*
X-1091000Y-472900D01*
X-1087200Y-472800D01*
X-1082700Y-473700D01*
X-1079000Y-473600D01*
X-1076500Y-472300D01*
X-1074700Y-470600D01*
X-1074300Y-467300D01*
X-1074800Y-465300D01*
X-1078800Y-463600D01*
X-1081600Y-462900D01*
X-1083400Y-462500D01*
X-1084800Y-461500D01*
X-1085000Y-458900D01*
X-1088100Y-459800D01*
X-1087200Y-462700D01*
X-1085000Y-463400D01*
X-1082000Y-464100D01*
X-1079600Y-465100D01*
X-1078200Y-466500D01*
X-1077700Y-468500D01*
X-1077500Y-470100D01*
X-1079200Y-472800D01*
X-1076800Y-471400D01*
X-1075300Y-470000D01*
X-1077300Y-470900D01*
X-1075000Y-468800D01*
X-1075200Y-466100D01*
X-1082700Y-462700D01*
X-1084200Y-462900D01*
X-1086600Y-461800D01*
X-1087200Y-460300D01*
X-1085800Y-459800D01*
X-1086600Y-461000D01*
X-1085300Y-460400D01*
X-1085600Y-461400D01*
X-1076700Y-466500D01*
X-1075900Y-467100D01*
X-1075700Y-468400D01*
X-1076800Y-469500D01*
X-1077800Y-466200D01*
X-1075900Y-468800D01*
G01X-1093780Y-468700D02*
X-1087100D01*
Y-469740D01*
X-1086800Y-470060D01*
X-1086520Y-470600D01*
X-1085820Y-470820D01*
X-1085660Y-471000D01*
X-1085120Y-471260D01*
X-1084400Y-471500D01*
X-1082360D01*
X-1080540Y-470600D01*
X-1080100Y-470140D01*
Y-469780D01*
X-1079840Y-469380D01*
X-1080380Y-467740D01*
X-1081440Y-466940D01*
X-1082560Y-466720D01*
X-1085740Y-465920D01*
X-1086940Y-465520D01*
X-1087600Y-465360D01*
X-1087740Y-465200D01*
X-1088540Y-464800D01*
X-1089140Y-464200D01*
X-1089540Y-464000D01*
X-1089800Y-463740D01*
X-1090000Y-463340D01*
X-1090180Y-463180D01*
X-1090500Y-462200D01*
Y-459800D01*
X-1090320Y-459260D01*
X-1090140Y-458500D01*
X-1090000Y-458260D01*
X-1089000Y-457260D01*
X-1088860Y-456940D01*
X-1085920Y-455480D01*
X-1083620Y-455100D01*
X-1082060Y-454900D01*
X-1080520D01*
X-1078580Y-455100D01*
X-1076240Y-455480D01*
X-1075120Y-455860D01*
X-1074800Y-456020D01*
X-1073680Y-456760D01*
X-1073160Y-457300D01*
X-1072620Y-458020D01*
X-1072500Y-458240D01*
Y-460300D01*
X-1078500D01*
Y-459200D01*
X-1079580Y-458380D01*
X-1080160Y-458100D01*
X-1082380D01*
X-1083280Y-458360D01*
X-1084020Y-458940D01*
X-1084340Y-459900D01*
X-1084060Y-460720D01*
X-1083740Y-461340D01*
X-1081860Y-462280D01*
X-1079400Y-462500D01*
X-1078660Y-462680D01*
X-1078100Y-462860D01*
X-1076500Y-463460D01*
X-1075320Y-463860D01*
X-1075060Y-464000D01*
X-1073820Y-465220D01*
X-1073480Y-466260D01*
X-1073300Y-467160D01*
Y-468420D01*
X-1073860Y-470700D01*
X-1074000Y-470960D01*
X-1075140Y-472300D01*
X-1075280Y-472440D01*
X-1076600Y-473380D01*
X-1077320Y-473740D01*
X-1079600Y-474500D01*
X-1088240D01*
X-1089160Y-474320D01*
X-1089920Y-474120D01*
X-1090860Y-473760D01*
X-1091560Y-473400D01*
X-1092700Y-472460D01*
X-1093180Y-471980D01*
X-1093340Y-471480D01*
X-1093520Y-471100D01*
X-1093700Y-470320D01*
X-1093780Y-468700D01*
G01X-1095100D02*
X-1092800D01*
G01X-1058300Y-469400D02*
X-1055400Y-467100D01*
X-1053900Y-463700D01*
X-1054400Y-461200D01*
X-1055900Y-459900D01*
X-1054800Y-463500D01*
X-1055400Y-463600D01*
X-1054600Y-464500D01*
X-1055700D01*
X-1055400Y-465300D01*
X-1056200Y-466800D01*
G01X-1059300Y-457700D02*
X-1059100Y-455600D01*
X-1055200Y-456300D01*
X-1052700Y-457900D01*
X-1051100Y-460800D01*
X-1050900Y-465200D01*
X-1052900Y-469400D01*
X-1055300Y-471900D01*
X-1059000Y-473500D01*
X-1066000D01*
X-1068000Y-471900D01*
X-1070200Y-468700D01*
X-1070600Y-464500D01*
X-1069000Y-460500D01*
X-1066000Y-457500D01*
X-1063000Y-456500D01*
X-1059200Y-456000D01*
X-1053000Y-458500D01*
X-1052000Y-461500D01*
Y-465700D01*
X-1053400Y-468600D01*
X-1055700Y-471000D01*
X-1058900Y-472600D01*
X-1063700Y-473000D01*
X-1065900Y-473600D01*
X-1068300Y-472900D01*
X-1070600Y-469300D01*
X-1065100Y-472600D01*
X-1060800Y-472200D01*
X-1057200Y-470700D01*
X-1055200Y-469100D01*
X-1053300Y-466500D01*
X-1052500Y-463400D01*
X-1052900Y-460100D01*
X-1057000Y-457400D01*
X-1058700Y-457200D01*
X-1057000Y-458500D01*
X-1055100Y-459800D01*
X-1053800Y-460900D01*
X-1053400Y-463100D01*
X-1053600Y-465600D01*
X-1054800Y-467500D01*
X-1056400Y-469200D01*
X-1058500Y-470200D01*
X-1060200Y-470700D01*
X-1061500Y-471400D01*
X-1063300Y-471600D01*
X-1065400Y-471500D01*
X-1069000Y-469300D01*
X-1069600Y-466400D01*
X-1069700Y-463700D01*
X-1068600Y-461200D01*
X-1066700Y-459200D01*
X-1063900Y-457600D01*
X-1061100Y-457000D01*
X-1059600D01*
X-1060200Y-457500D01*
X-1063300Y-458000D01*
X-1065300Y-459500D01*
X-1066900Y-460600D01*
X-1067900Y-462100D01*
X-1068800Y-464300D01*
X-1068700Y-466900D01*
X-1068200Y-469100D01*
X-1066900Y-470200D01*
X-1064300Y-470900D01*
X-1065700Y-469300D01*
X-1065800Y-465900D01*
X-1065300Y-462900D01*
X-1061200Y-458200D01*
X-1063600Y-458900D01*
X-1066400Y-461300D01*
X-1067800Y-464200D01*
Y-467200D01*
X-1067400Y-469300D01*
X-1066300Y-469700D01*
X-1067100Y-466400D01*
X-1066600Y-463400D01*
X-1064700Y-460000D01*
X-1062600Y-458800D01*
X-1065300Y-461700D01*
X-1066700Y-467400D01*
G01X-1060840Y-455100D02*
X-1057160D01*
X-1055260Y-455480D01*
X-1054740Y-455640D01*
X-1053380Y-456420D01*
X-1052660Y-456800D01*
X-1052020Y-457420D01*
X-1051820Y-458020D01*
X-1051200Y-458660D01*
X-1051000Y-459060D01*
X-1050840Y-459200D01*
X-1050700Y-459780D01*
Y-460140D01*
X-1050400Y-460460D01*
X-1050280Y-460680D01*
X-1050100Y-461740D01*
Y-464240D01*
X-1050280Y-465160D01*
X-1050480Y-465980D01*
X-1050680Y-467120D01*
X-1051220Y-468180D01*
X-1051840Y-469020D01*
X-1052040Y-469600D01*
X-1052740Y-470500D01*
X-1054480Y-472240D01*
X-1055000Y-472580D01*
X-1055420Y-472780D01*
X-1056220Y-473380D01*
X-1056920Y-473740D01*
X-1059380Y-474500D01*
X-1065600D01*
X-1067860Y-473740D01*
X-1068160Y-473600D01*
X-1069500Y-472460D01*
X-1069820Y-472120D01*
X-1070380Y-471200D01*
X-1071140Y-469860D01*
X-1071300Y-469400D01*
Y-464580D01*
X-1071120Y-463880D01*
X-1070740Y-462900D01*
X-1070540Y-462320D01*
X-1069980Y-461000D01*
X-1068840Y-459500D01*
X-1066900Y-457560D01*
X-1066180Y-457020D01*
X-1065400Y-456620D01*
X-1064440Y-456040D01*
X-1063500Y-455660D01*
X-1062940Y-455480D01*
X-1060840Y-455100D01*
G01X-1057800Y-458580D02*
X-1057000Y-459120D01*
X-1056760Y-459840D01*
X-1056340Y-460460D01*
X-1056100Y-461640D01*
Y-463760D01*
X-1056320Y-464860D01*
X-1056720Y-466060D01*
X-1056940Y-466920D01*
X-1057200Y-467460D01*
X-1057640Y-467880D01*
X-1058040Y-468480D01*
X-1059960Y-470420D01*
X-1061020Y-470840D01*
X-1061420Y-471100D01*
X-1062720D01*
X-1063340Y-470840D01*
X-1063860Y-470600D01*
X-1064360Y-470080D01*
X-1064820Y-469400D01*
X-1065100Y-468840D01*
Y-464920D01*
X-1064880Y-464120D01*
X-1064420Y-462780D01*
X-1064160Y-462520D01*
X-1063620Y-461700D01*
X-1063200Y-460840D01*
X-1062500Y-460140D01*
X-1062120Y-459860D01*
X-1061720Y-459360D01*
X-1060600Y-458580D01*
X-1060040Y-458300D01*
X-1058360D01*
X-1057800Y-458580D01*
G01X-1040300Y-459100D02*
X-1041400Y-464800D01*
G01X-1044800Y-458200D02*
X-1041400D01*
X-1044300Y-472700D01*
X-1047400Y-472300D01*
X-1044100Y-458800D01*
X-1042400Y-459100D01*
X-1045100Y-471900D01*
X-1046500D01*
X-1043400Y-459700D01*
X-1045600Y-471500D01*
G01X-1036600Y-449900D02*
X-1036800Y-451300D01*
X-1038600Y-452400D01*
X-1039800Y-456100D01*
X-1033700Y-456500D01*
X-1032300Y-452100D01*
X-1028400Y-452000D01*
X-1028900Y-455400D01*
X-1027200Y-456600D01*
X-1025900Y-456800D01*
X-1026200Y-458200D01*
X-1030000Y-458400D01*
X-1031800Y-468900D01*
X-1030400Y-471700D01*
X-1029400D01*
X-1029600Y-473300D01*
X-1033100Y-473400D01*
X-1036100Y-472800D01*
X-1036200Y-470500D01*
X-1035900Y-467100D01*
X-1034400Y-461400D01*
X-1033800Y-458800D01*
X-1033500Y-458400D01*
X-1035000Y-458200D01*
X-1039600D01*
X-1040800Y-458300D01*
X-1043600Y-473200D01*
X-1048000Y-473000D01*
X-1045100Y-459400D01*
X-1044900Y-458400D01*
X-1048700D01*
X-1048100Y-456600D01*
X-1044900Y-456400D01*
X-1045200Y-457700D01*
X-1047600Y-457500D01*
X-1026500D01*
G01X-1049580Y-459100D02*
X-1048740Y-455700D01*
X-1044900D01*
Y-454780D01*
X-1044720Y-454060D01*
X-1044340Y-452920D01*
X-1043940Y-452120D01*
X-1043740Y-451520D01*
X-1043600Y-451260D01*
X-1042340Y-450000D01*
X-1042080Y-449860D01*
X-1040580Y-449480D01*
X-1039440Y-449300D01*
X-1036140D01*
X-1035440Y-449400D01*
X-1035480Y-449540D01*
X-1035680Y-450360D01*
X-1035880Y-451280D01*
X-1036000Y-451900D01*
X-1036740D01*
X-1037060Y-452200D01*
X-1037860Y-452600D01*
X-1038220Y-452980D01*
X-1038480Y-453740D01*
X-1038960Y-455700D01*
X-1034020D01*
X-1033720Y-455080D01*
X-1033500Y-453400D01*
X-1032940Y-451100D01*
X-1027260D01*
X-1027280Y-451180D01*
X-1027480Y-452780D01*
X-1027860Y-454280D01*
X-1028100Y-454760D01*
Y-455700D01*
X-1024800D01*
X-1024880Y-455940D01*
X-1025080Y-456940D01*
X-1025280Y-457540D01*
X-1025480Y-458560D01*
X-1025620Y-459100D01*
X-1029100D01*
Y-460000D01*
X-1029280Y-460540D01*
X-1029480Y-461540D01*
X-1029680Y-462140D01*
X-1029880Y-462960D01*
X-1030100Y-464000D01*
X-1030280Y-465560D01*
X-1030480Y-466140D01*
X-1030680Y-467140D01*
X-1030880Y-467740D01*
X-1031040Y-468400D01*
X-1031300Y-468660D01*
Y-469800D01*
X-1030300Y-470560D01*
X-1029940Y-470900D01*
X-1028220D01*
X-1028680Y-472780D01*
X-1028880Y-474120D01*
Y-474140D01*
X-1030720Y-474300D01*
X-1032860D01*
X-1034380Y-474120D01*
X-1035860Y-473740D01*
X-1036640Y-473280D01*
X-1036960Y-472660D01*
X-1037100Y-472280D01*
Y-470160D01*
X-1036920Y-469260D01*
X-1036700Y-468640D01*
X-1036500Y-466840D01*
X-1036320Y-466260D01*
X-1036120Y-465260D01*
X-1035920Y-464660D01*
X-1035720Y-463660D01*
X-1035520Y-463060D01*
X-1035320Y-462060D01*
X-1035120Y-461440D01*
X-1034820Y-459100D01*
X-1039900D01*
Y-460220D01*
X-1040280Y-461780D01*
X-1040480Y-463380D01*
X-1041280Y-466540D01*
X-1041480Y-467140D01*
X-1041700Y-468200D01*
X-1041880Y-469760D01*
X-1042080Y-470340D01*
X-1042280Y-471360D01*
X-1042480Y-472140D01*
X-1042680Y-472740D01*
X-1042880Y-473740D01*
X-1042940Y-473900D01*
X-1049140D01*
X-1048300Y-470620D01*
X-1048100Y-469020D01*
X-1047920Y-468260D01*
X-1047720Y-467660D01*
X-1047520Y-466660D01*
X-1047320Y-466060D01*
X-1047120Y-465060D01*
X-1046920Y-464460D01*
X-1046700Y-463400D01*
X-1046500Y-462020D01*
X-1046140Y-460500D01*
X-1045900Y-460040D01*
Y-459100D01*
X-1049580D01*
G01X-1038400Y-451100D02*
X-1040600Y-455800D01*
X-1043300D01*
X-1041400Y-451300D01*
X-1038900Y-451000D01*
X-1041200Y-455000D01*
X-1042000Y-455100D01*
X-1040500Y-452000D01*
G01X-1037500Y-449800D02*
X-1037800Y-451000D01*
X-1038500Y-450100D01*
X-1042000Y-450700D01*
X-1043100Y-452300D01*
X-1044100Y-455100D01*
X-1044200Y-456600D01*
X-1036600Y-456800D01*
G01X-1031100Y-472500D02*
X-1031400Y-470900D01*
X-1031900Y-472200D01*
X-1035200D01*
Y-467600D01*
X-1032000Y-453700D01*
X-1030500Y-453800D01*
X-1030000Y-456700D01*
X-1033400Y-471900D01*
X-1034300Y-471600D01*
X-1034200Y-467100D01*
X-1031400Y-454500D01*
X-1030700Y-456500D01*
X-1033700Y-470600D01*
X-1032700Y-461100D01*
G01X-1032000Y-452900D02*
X-1029300D01*
X-1028000Y-457000D01*
X-1029500Y-453600D01*
X-1029100Y-457300D01*
X-1032800Y-472800D01*
X-1030200Y-472600D01*
G54D22*
X-1327756Y-127795D03*
X-457677D03*
G54D13*
X-1658500Y-31000D03*
X-1639488Y-27500D03*
X-1644488D03*
X-1654488Y-27300D03*
X-1649488Y-27400D03*
X-1633000Y-135500D03*
X-1634488Y-27600D03*
X-1629488Y-27700D03*
X-1618400Y-71600D03*
X-1618300Y-63100D03*
X-1621600Y-61100D03*
Y-65100D03*
X-1618500Y-67200D03*
X-1621600Y-69400D03*
X-1615000Y-37500D03*
Y-27500D03*
Y-32500D03*
X-1610000Y-37500D03*
Y-32500D03*
Y-27500D03*
X-1600000Y-37500D03*
Y-27500D03*
Y-32500D03*
X-1605000Y-37500D03*
Y-32500D03*
Y-27500D03*
X-1595000Y-37500D03*
Y-32500D03*
Y-27500D03*
X-1580000Y-42500D03*
Y-47500D03*
X-1585000Y-42500D03*
Y-47500D03*
X-1590000D03*
Y-42500D03*
X-1580000Y-27500D03*
Y-32500D03*
Y-37500D03*
X-1585000Y-32500D03*
Y-27500D03*
Y-37500D03*
X-1590000D03*
Y-32500D03*
Y-27500D03*
X-1565000Y-42500D03*
Y-47500D03*
X-1575000Y-42500D03*
Y-47500D03*
X-1570000Y-42500D03*
Y-47500D03*
X-1565000Y-27500D03*
Y-32500D03*
Y-37500D03*
X-1575000Y-27500D03*
Y-32500D03*
Y-37500D03*
X-1570000Y-32500D03*
Y-27500D03*
Y-37500D03*
X-1555000Y-47500D03*
Y-42500D03*
X-1550000Y-47500D03*
Y-42500D03*
X-1560000D03*
Y-47500D03*
X-1545000D03*
Y-42500D03*
Y-37500D03*
Y-32500D03*
Y-27500D03*
X-1555000Y-37500D03*
Y-32500D03*
Y-27500D03*
X-1550000Y-37500D03*
Y-32500D03*
Y-27500D03*
X-1560000D03*
Y-32500D03*
Y-37500D03*
X-1530000Y-120300D03*
X-1535000Y-42500D03*
Y-47500D03*
X-1540000Y-42500D03*
Y-47500D03*
Y-37500D03*
Y-32500D03*
X-1535000Y-37500D03*
X-1530063Y-12160D03*
Y-17160D03*
Y-22160D03*
X-1535063Y-12160D03*
Y-17160D03*
X-1515063Y-12160D03*
Y-17160D03*
Y-22160D03*
X-1525063Y-12160D03*
Y-17160D03*
X-1520063Y-12160D03*
Y-17160D03*
X-1525063Y-22160D03*
X-1520063D03*
X-1500063Y-12160D03*
Y-17160D03*
Y-22160D03*
X-1510063Y-12160D03*
Y-17160D03*
X-1505063Y-12160D03*
Y-17160D03*
X-1510063Y-22160D03*
X-1505063D03*
X-1497043Y-164390D03*
X-1486693Y-166890D03*
X-1497043Y-149390D03*
X-1486693Y-161890D03*
X-1491652Y-151849D03*
X-1491693Y-156890D03*
X-1486693Y-151890D03*
Y-156890D03*
X-1497043Y-144390D03*
X-1491693Y-136890D03*
X-1486693Y-141890D03*
Y-146890D03*
Y-136890D03*
X-1497043Y-124390D03*
Y-129390D03*
X-1486693Y-121890D03*
Y-126890D03*
X-1491693Y-131890D03*
X-1486693D03*
X-1497043Y-109390D03*
Y-104390D03*
X-1486693Y-101890D03*
Y-106890D03*
X-1491693Y-111890D03*
Y-116890D03*
X-1486693Y-111890D03*
Y-116890D03*
X-1497043Y-89390D03*
X-1486693Y-86890D03*
X-1491693Y-91890D03*
Y-96890D03*
X-1486693Y-91890D03*
Y-96890D03*
X-1491693Y-76890D03*
X-1486693Y-81890D03*
X-1497000Y-81700D03*
X-1496693Y-76890D03*
Y-71890D03*
X-1486693D03*
X-1491693D03*
X-1485063Y-12160D03*
Y-17160D03*
Y-22160D03*
X-1495063Y-12160D03*
Y-17160D03*
X-1490063Y-12160D03*
Y-17160D03*
X-1495063Y-22160D03*
X-1490063D03*
X-1466693Y-166890D03*
X-1476693D03*
X-1471693D03*
X-1481693D03*
X-1476693Y-161890D03*
X-1481693Y-156890D03*
Y-151890D03*
X-1471693D03*
Y-156890D03*
X-1466693Y-161890D03*
Y-151890D03*
X-1476693D03*
X-1471693Y-161890D03*
X-1466693Y-156890D03*
X-1476693D03*
X-1481693Y-161890D03*
Y-136890D03*
X-1471693D03*
X-1466693Y-141890D03*
X-1476693D03*
X-1466693Y-146890D03*
X-1476693D03*
X-1471693Y-141890D03*
X-1466693Y-136890D03*
X-1476693D03*
X-1471693Y-146890D03*
X-1481693Y-141890D03*
Y-146890D03*
Y-131890D03*
X-1466693Y-121890D03*
X-1476693D03*
X-1466693Y-126890D03*
X-1476693D03*
X-1471693Y-131890D03*
X-1466693D03*
X-1471693Y-121890D03*
X-1476693Y-131890D03*
X-1471693Y-126890D03*
X-1481693Y-121890D03*
Y-126890D03*
Y-111890D03*
Y-116890D03*
X-1466693Y-101890D03*
X-1476693D03*
X-1466693Y-106890D03*
X-1476693D03*
X-1471693Y-111890D03*
Y-116890D03*
X-1466693Y-111890D03*
X-1471693Y-101890D03*
X-1476693Y-111890D03*
X-1466693Y-116890D03*
X-1471693Y-106890D03*
X-1476693Y-116890D03*
X-1481693Y-101890D03*
Y-106890D03*
Y-86890D03*
X-1471693D03*
X-1481693Y-91890D03*
Y-96890D03*
X-1466693Y-86890D03*
X-1476693D03*
X-1471693Y-91890D03*
Y-96890D03*
X-1476693Y-91890D03*
X-1466693D03*
X-1476693Y-96890D03*
X-1466693D03*
X-1481693Y-81890D03*
X-1471693D03*
X-1476693D03*
Y-71890D03*
X-1481693D03*
X-1471693D03*
X-1476693Y-76890D03*
X-1481693D03*
X-1471693D03*
X-1466693D03*
Y-81890D03*
Y-71890D03*
X-1470063Y-12160D03*
Y-17160D03*
Y-22160D03*
X-1480063Y-12160D03*
Y-17160D03*
X-1475063Y-12160D03*
Y-17160D03*
X-1480063Y-22160D03*
X-1461693Y-166890D03*
Y-151890D03*
Y-156890D03*
Y-161890D03*
Y-136890D03*
Y-141890D03*
Y-146890D03*
Y-131890D03*
Y-121890D03*
Y-126890D03*
Y-111890D03*
Y-116890D03*
Y-101890D03*
Y-106890D03*
Y-86890D03*
Y-91890D03*
Y-96890D03*
Y-81890D03*
Y-71890D03*
X-1452000Y-74000D03*
X-1461693Y-76890D03*
X-1452000Y-78200D03*
X-1452100Y-82200D03*
X-1451700Y-65700D03*
X-1451500Y-61800D03*
X-1451800Y-69600D03*
X-1465063Y-12160D03*
Y-17160D03*
Y-22160D03*
X-1450000Y-175000D03*
Y-162500D03*
X-1437500D03*
X-1450000Y-150000D03*
Y-137500D03*
Y-125000D03*
X-1437500Y-100000D03*
X-1436500Y-87500D03*
X-1450000D03*
X-1443500Y-94000D03*
X-1450000Y-100000D03*
X-1449100Y-71800D03*
X-1448900Y-76100D03*
X-1449000Y-80300D03*
X-1448800Y-63800D03*
X-1448700Y-59900D03*
X-1448800Y-67700D03*
X-1434892Y-40389D03*
Y-50389D03*
Y-45389D03*
Y-35389D03*
X-1435000Y1000D03*
X-1425000Y-175000D03*
Y-162500D03*
X-1430500Y-93500D03*
X-1424500Y-100000D03*
X-1425000Y-87500D03*
X-1430000Y-75400D03*
X-1431500Y-81000D03*
X-1425000Y-62500D03*
X-1419892Y-50389D03*
Y-40389D03*
Y-45389D03*
X-1427392Y-50389D03*
Y-45389D03*
Y-40389D03*
X-1419892Y-35389D03*
X-1427392D03*
X-1419500Y-18000D03*
X-1432000D03*
X-1420000Y14500D03*
X-1412500Y-175000D03*
Y-162500D03*
X-1406250Y-106250D03*
X-1412000Y-100500D03*
X-1418500Y-93500D03*
X-1412000Y-87000D03*
X-1406250Y-82500D03*
X-1412500Y-75000D03*
Y-62500D03*
X-1404892Y-50389D03*
Y-45389D03*
Y-40389D03*
X-1412392Y-50389D03*
Y-45389D03*
Y-40389D03*
X-1404892Y-35389D03*
X-1412392D03*
X-1407000Y-18000D03*
X-1407500Y14500D03*
X-1387500Y-175000D03*
X-1400000D03*
Y-162500D03*
X-1387500D03*
X-1400000Y-150000D03*
X-1387300Y-133200D03*
X-1387500Y-137500D03*
Y-125000D03*
X-1400100Y-131550D03*
X-1400000Y-125000D03*
X-1395000Y-106250D03*
X-1400000Y-112500D03*
X-1387500D03*
X-1400500Y-96500D03*
Y-87000D03*
X-1391000Y-96500D03*
X-1393750Y-82500D03*
X-1400000Y-75000D03*
X-1387500D03*
Y-62500D03*
X-1400000D03*
X-1389892Y-40389D03*
Y-45389D03*
Y-50389D03*
X-1397392Y-40389D03*
Y-45389D03*
Y-50389D03*
X-1389892Y-35389D03*
X-1397392D03*
X-1394500Y-18000D03*
X-1395000Y-8000D03*
Y-500D03*
X-1395518Y14053D03*
X-1380000Y-106250D03*
X-1381250Y-82500D03*
X-1375000Y-75000D03*
Y-62500D03*
X-1373800Y-52900D03*
X-1382392Y-40389D03*
Y-45389D03*
Y-50389D03*
Y-35389D03*
X-1382500Y-8000D03*
Y-18000D03*
Y7000D03*
Y-500D03*
Y14500D03*
X-1363750Y-106250D03*
X-1356250Y-82500D03*
X-1362500Y-75000D03*
Y-62500D03*
X-1356700Y-25600D03*
X-1357500Y-8000D03*
X-1370000D03*
Y-500D03*
X-1357500Y7000D03*
Y-500D03*
X-1370000Y7000D03*
Y14500D03*
X-1357500D03*
X-1350600Y-75000D03*
X-1343200Y-82700D03*
X-1350000Y-62500D03*
X-1345000Y-8000D03*
Y-500D03*
Y7000D03*
Y14500D03*
X-1330400Y-74900D03*
X-1337500Y-62500D03*
X-1332500Y-27500D03*
X-1335400Y-37600D03*
X-1332500Y7000D03*
Y-500D03*
Y14500D03*
X-1322228Y-88400D03*
X-1316728Y-89200D03*
X-1321000Y-94850D03*
X-1313040Y-80810D03*
X-1317700Y-72700D03*
X-1310559Y-74200D03*
X-1317700Y-60200D03*
X-1310559Y-68700D03*
Y-63200D03*
Y-57700D03*
X-1310600Y-46690D03*
X-1310559Y-41200D03*
Y-52200D03*
Y-35700D03*
X-1320000Y-500D03*
Y7000D03*
X-1318500Y-6000D03*
X-1320000Y14500D03*
X-1306850Y-95000D03*
X-1300350Y-88500D03*
X-1293500Y-80000D03*
X-1302400Y-84100D03*
X-1297995Y-58405D03*
X-1298400Y-63200D03*
X-1298800Y-30200D03*
X-1295400Y-13400D03*
X-1307500Y7000D03*
X-1295000Y14500D03*
X-1307500D03*
X-1279429Y-180579D03*
X-1282500Y14500D03*
X-1269513Y-183637D03*
X-1266313D03*
X-1271813Y-181337D03*
X-1264267Y-181074D03*
X-1271813Y-185937D03*
X-1264013D03*
X-1276860Y-178030D03*
X-1263189Y-177998D03*
X-1272638D03*
X-1271088Y-151780D03*
X-1267888D03*
X-1274213Y-157350D03*
X-1264764D03*
X-1265588Y-154080D03*
X-1273388D03*
Y-149480D03*
X-1265588D03*
X-1261625Y-144435D03*
X-1263925Y-146735D03*
X-1264060Y-141950D03*
X-1270000Y14500D03*
X-1245710Y-189905D03*
Y-186705D03*
X-1248010Y-184405D03*
Y-192205D03*
X-1247979Y-177933D03*
X-1250591Y-179920D03*
X-1253740Y-177998D03*
X-1248860Y-150200D03*
X-1246390Y-153490D03*
X-1258425Y-144435D03*
X-1249016Y-144800D03*
X-1250660Y-140480D03*
X-1256125Y-146735D03*
Y-142135D03*
X-1257500Y-57500D03*
Y-45000D03*
Y-20000D03*
Y14500D03*
X-1232340Y-185380D03*
X-1235540D03*
X-1230040Y-183080D03*
Y-187680D03*
X-1237840Y-183080D03*
Y-187680D03*
X-1243410Y-184405D03*
Y-192205D03*
X-1237992Y-179850D03*
X-1234843Y-177998D03*
X-1241142Y-178998D03*
X-1244291Y-177998D03*
X-1236418Y-157350D03*
X-1236310Y-140390D03*
X-1230093Y-134350D03*
X-1233293D03*
X-1235593Y-136650D03*
Y-132050D03*
X-1245000Y-70000D03*
X-1232500Y-57500D03*
X-1245000Y-45000D03*
Y-20000D03*
X-1232500D03*
X-1245000Y14500D03*
X-1232500D03*
X-1215945Y-177998D03*
X-1225394D03*
X-1220590Y-149900D03*
X-1223790D03*
X-1226969Y-157350D03*
X-1218290Y-152200D03*
X-1226090D03*
X-1218290Y-147600D03*
X-1226090D03*
X-1227793Y-136650D03*
Y-132050D03*
X-1220000Y14500D03*
X-1202580Y-176300D03*
X-1209420Y-167360D03*
X-1206220D03*
X-1211720Y-169660D03*
Y-165060D03*
X-1203920D03*
Y-169660D03*
X-1202100Y-103200D03*
X-1199500Y5400D03*
Y-3000D03*
X-1207500Y14500D03*
X-1191200Y-40500D03*
X-1191500Y-34000D03*
X-1191900Y-29500D03*
X-1190800Y-23450D03*
X-1191000Y-18250D03*
X-1191200Y-12128D03*
X-1192359Y-5800D03*
X-1191500Y0D03*
X-1195000Y14500D03*
X-1176100Y-114800D03*
X-1170300Y-114600D03*
X-1172500Y-44000D03*
X-1173200Y-49700D03*
X-1178900Y-46700D03*
X-1179000Y-40500D03*
X-1172500Y-38500D03*
X-1171800Y-26950D03*
X-1178800Y-34800D03*
X-1177800Y-12100D03*
X-1172000Y-10750D03*
X-1171500Y-21750D03*
X-1171800Y-16250D03*
X-1178800Y-5800D03*
X-1172100Y-5400D03*
X-1170000Y14500D03*
X-1182500D03*
X-1160000Y-115100D03*
X-1154200Y-103100D03*
X-1154400Y-107900D03*
X-1160000Y-38500D03*
X-1159700Y-43900D03*
X-1159800Y-33100D03*
X-1157500Y14500D03*
X-1137500Y-15000D03*
Y-2500D03*
X-1145000Y14500D03*
X-1124878Y-175150D03*
X-1134579Y-179850D03*
X-1123450Y-155183D03*
X-1120250D03*
X-1125750Y-152883D03*
Y-157483D03*
X-1126575Y-147990D03*
Y-136730D03*
X-1124800Y-129000D03*
X-1120400D03*
X-1125000Y-101700D03*
X-1126000Y-15000D03*
Y-2500D03*
X-1120000Y14500D03*
X-1132500D03*
X-1113328Y-182209D03*
X-1107828Y-182300D03*
X-1114979Y-170700D03*
X-1106979D03*
X-1117950Y-157483D03*
Y-152883D03*
X-1117126Y-136730D03*
X-1107677Y-148090D03*
Y-136730D03*
X-1117126Y-148090D03*
X-1108703Y-118455D03*
Y-121655D03*
X-1111003Y-123960D03*
X-1106403D03*
X-1114500Y-129000D03*
X-1110500D03*
X-1118701Y-101759D03*
X-1112402Y-101600D03*
X-1109300Y-104200D03*
X-1106102Y-102100D03*
X-1106403Y-116160D03*
X-1111003D03*
X-1107700Y-73400D03*
Y-63100D03*
X-1107800Y-68200D03*
X-1111500Y-15000D03*
Y-2500D03*
X-1107500Y14500D03*
X-1096200Y-175150D03*
X-1098228Y-148090D03*
Y-136730D03*
X-1102953Y-104200D03*
X-1099010Y-104183D03*
X-1099400Y-90200D03*
X-1093400D03*
X-1100000Y-2500D03*
X-1095000Y14500D03*
X-1084600Y-179850D03*
X-1073000Y-90300D03*
X-1082500Y14500D03*
X-1063600Y-56600D03*
X-1062000Y-29200D03*
X-1061900Y-5200D03*
X-1070000Y14500D03*
X-1045100Y-52900D03*
X-1044300Y-47661D03*
X-1045400Y-38000D03*
X-1051400Y-26000D03*
X-1041300Y-10100D03*
Y-16500D03*
X-1050811Y2600D03*
X-1045000Y14500D03*
X-1033843Y-128576D03*
X-1032500Y14500D03*
X-1017670Y-123250D03*
X-1022140Y-122960D03*
X-1015729Y-100550D03*
X-1012638Y-85886D03*
X-1015179Y-74100D03*
X-1012638Y-70873D03*
Y-56060D03*
X-1012860Y-41250D03*
X-1020000Y14500D03*
X-1003380Y-86986D03*
X-1008429Y-91400D03*
X-999960Y-90706D03*
X-996670Y-75460D03*
X-1008719Y-75998D03*
X-999860Y-75848D03*
Y-60885D03*
X-1003780Y-56060D03*
X-994280Y-40890D03*
X-997500Y-7500D03*
X-1007500Y14500D03*
X-995000D03*
X-983000Y-7500D03*
X-982500Y14500D03*
X-969331Y-100849D03*
Y-85886D03*
X-965512Y-90706D03*
X-971779Y-73800D03*
X-965412Y-75848D03*
Y-45922D03*
X-970000Y14500D03*
X-956653Y-90706D03*
X-960273Y-101049D03*
X-953250Y-75340D03*
X-956553Y-75848D03*
X-957779Y-57700D03*
X-956553Y-60885D03*
Y-45922D03*
X-957500Y-7500D03*
Y14500D03*
X-945000Y-7500D03*
X-932500Y14500D03*
X-945000D03*
X-922500Y-170000D03*
Y-159500D03*
Y-120000D03*
Y-132500D03*
Y-107500D03*
Y-95000D03*
Y-70000D03*
Y-82500D03*
Y-57500D03*
Y-45000D03*
Y-20000D03*
Y-7500D03*
Y5000D03*
X-922000Y14500D03*
X-910000Y-170000D03*
Y-159500D03*
Y-132500D03*
Y-107500D03*
Y-95000D03*
Y-82500D03*
Y-70000D03*
Y-57500D03*
Y-45000D03*
Y-7500D03*
Y-20000D03*
Y5000D03*
X-909500Y14500D03*
X-897500Y-170000D03*
X-885000D03*
Y-159500D03*
X-897500D03*
X-885000Y-132500D03*
X-897500D03*
X-885000Y-107500D03*
X-897500D03*
Y-95000D03*
X-885000D03*
Y-82500D03*
X-897500Y-70000D03*
Y-82500D03*
X-885000Y-70000D03*
Y-57500D03*
X-897500D03*
Y-45000D03*
X-885000D03*
Y-7500D03*
X-897500Y-20000D03*
X-885000D03*
X-897500Y-7500D03*
Y5000D03*
X-885000D03*
Y14500D03*
X-897500D03*
X-872500Y-170000D03*
Y-159500D03*
Y-132500D03*
Y-107500D03*
Y-95000D03*
Y-70000D03*
Y-82500D03*
Y-57500D03*
Y-45000D03*
Y-20000D03*
Y-7500D03*
Y5000D03*
Y14500D03*
X-860000Y-170000D03*
Y-159500D03*
Y-132500D03*
Y-107500D03*
Y-95000D03*
Y-82500D03*
Y-70000D03*
Y-57500D03*
Y-7500D03*
Y-20000D03*
Y5000D03*
Y14500D03*
X-847500Y-170000D03*
Y-159500D03*
Y-132500D03*
Y-107500D03*
Y-95000D03*
Y-70000D03*
Y-82500D03*
Y-57500D03*
Y-45000D03*
Y-20000D03*
Y-7500D03*
Y5000D03*
X-848000Y14500D03*
X-822500Y-170000D03*
X-835000Y-159500D03*
X-822500D03*
Y-145000D03*
X-835000Y-132500D03*
X-822500Y-120000D03*
Y-132500D03*
X-835000Y-120000D03*
Y-107500D03*
X-822500D03*
Y-95000D03*
X-835000D03*
Y-82500D03*
X-822500Y-70000D03*
Y-82500D03*
X-835000Y-70000D03*
Y-57500D03*
X-822500D03*
Y-45000D03*
X-835000D03*
X-822500Y-20000D03*
Y-7500D03*
X-835000Y-20000D03*
X-822500Y5000D03*
X-835500Y14500D03*
X-822500D03*
X-810000Y-170000D03*
Y-157500D03*
Y-145000D03*
Y-132500D03*
Y-120000D03*
Y-70000D03*
Y-57500D03*
Y-45000D03*
Y-7500D03*
Y-20000D03*
Y5000D03*
Y14500D03*
X-797500Y-120000D03*
Y-70000D03*
Y-57500D03*
Y-45000D03*
Y-20000D03*
Y-7500D03*
Y5000D03*
Y14500D03*
X-785500Y-120000D03*
X-785000Y-70000D03*
Y-57500D03*
Y-45000D03*
Y-7500D03*
Y-20000D03*
Y5000D03*
Y14500D03*
X-772500Y-170000D03*
Y-145000D03*
X-760000D03*
Y-132500D03*
X-772500Y-120000D03*
Y-132500D03*
X-760000Y-120000D03*
Y-107500D03*
X-772500D03*
Y-95000D03*
X-760000D03*
Y-82500D03*
X-772500Y-70000D03*
Y-82500D03*
X-760000Y-70000D03*
Y-57500D03*
X-772500D03*
Y-45000D03*
X-760000D03*
Y-7500D03*
X-772500Y-20000D03*
X-760000D03*
X-772500Y-7500D03*
Y5000D03*
X-760000D03*
Y14500D03*
X-772500D03*
X-747500Y-57500D03*
Y-45000D03*
Y-20000D03*
Y-7500D03*
Y5000D03*
Y14500D03*
X-735000Y-57500D03*
Y-45000D03*
Y-7500D03*
Y-20000D03*
Y5000D03*
Y14500D03*
X-722500Y-57500D03*
Y-45000D03*
Y-20000D03*
Y-7500D03*
Y5000D03*
Y14500D03*
X-697500Y-45000D03*
X-710000D03*
X-697500Y-20000D03*
X-710000Y-7500D03*
X-697500D03*
X-710000Y-20000D03*
X-697500Y5000D03*
X-710000D03*
Y14500D03*
X-697500D03*
X-685000Y-7500D03*
Y-20000D03*
Y5000D03*
Y14500D03*
X-672500Y-45000D03*
Y-20000D03*
Y-7500D03*
Y5000D03*
Y14500D03*
X-649700Y-117200D03*
X-655500Y-37500D03*
Y-25500D03*
Y-12500D03*
Y-500D03*
X-660000Y14500D03*
X-643700Y-125400D03*
X-642500Y-25500D03*
Y-37500D03*
Y-12500D03*
X-632500Y14500D03*
X-645000D03*
X-626964Y-164390D03*
X-616614Y-166890D03*
X-621614Y-156890D03*
X-621573Y-151849D03*
X-616614Y-161890D03*
X-627200Y-151300D03*
X-616614Y-151890D03*
Y-156890D03*
X-621614Y-136890D03*
X-616614Y-146890D03*
Y-141890D03*
X-626900Y-141300D03*
X-616614Y-136890D03*
X-621614Y-131890D03*
X-616614Y-126890D03*
Y-121890D03*
X-621614D03*
X-628700Y-130100D03*
X-616614Y-131890D03*
X-621614Y-116890D03*
Y-111890D03*
X-626964Y-104390D03*
Y-109390D03*
X-616614Y-106890D03*
Y-101890D03*
Y-111890D03*
Y-116890D03*
X-621614Y-96890D03*
Y-91890D03*
X-626964Y-89390D03*
X-616614Y-86890D03*
Y-91890D03*
Y-96890D03*
Y-76890D03*
Y-81890D03*
X-626625Y-81614D03*
X-626614Y-76890D03*
Y-71890D03*
X-621614D03*
X-616614D03*
X-616000Y-37500D03*
X-630000Y-25500D03*
Y-37500D03*
X-616000Y-25500D03*
X-630000Y-12500D03*
X-616000D03*
Y14500D03*
X-606614Y-166890D03*
X-601614D03*
X-611614D03*
X-601614Y-156890D03*
Y-151890D03*
X-611614D03*
Y-156890D03*
X-606614Y-161890D03*
Y-151890D03*
X-601614Y-161890D03*
X-606614Y-156890D03*
X-611614Y-161890D03*
X-606614Y-146890D03*
Y-141890D03*
X-601614Y-136890D03*
X-611614D03*
X-601614Y-141890D03*
X-606614Y-136890D03*
X-601614Y-146890D03*
X-611614Y-141890D03*
Y-146890D03*
X-601614Y-131890D03*
X-606614Y-126890D03*
Y-121890D03*
X-611614Y-131890D03*
X-601614Y-121890D03*
X-606614Y-131890D03*
X-601614Y-126890D03*
X-611614Y-121890D03*
Y-126890D03*
X-601614Y-116890D03*
Y-111890D03*
X-606614Y-106890D03*
Y-101890D03*
X-611614Y-116890D03*
Y-111890D03*
X-601614Y-101890D03*
X-606614Y-111890D03*
X-601614Y-106890D03*
X-606614Y-116890D03*
X-611614Y-101890D03*
Y-106890D03*
Y-86890D03*
X-601614D03*
Y-96890D03*
Y-91890D03*
X-606614Y-86890D03*
X-611614Y-96890D03*
Y-91890D03*
X-606614D03*
Y-96890D03*
X-611614Y-81890D03*
X-601614D03*
X-606614D03*
Y-71890D03*
X-611614D03*
X-601614D03*
X-606614Y-76890D03*
X-611614D03*
X-601614D03*
X-602500Y-37500D03*
Y-25000D03*
Y-12500D03*
Y0D03*
Y12500D03*
X-596614Y-166890D03*
X-591614D03*
X-591200Y-179700D03*
X-591614Y-156890D03*
Y-151890D03*
X-596614Y-161890D03*
Y-151890D03*
X-591614Y-161890D03*
X-596614Y-156890D03*
X-591614Y-136890D03*
X-596614Y-146890D03*
Y-141890D03*
X-591614D03*
X-596614Y-136890D03*
X-591614Y-146890D03*
Y-131890D03*
X-596614Y-126890D03*
Y-121890D03*
X-591614D03*
X-596614Y-131890D03*
X-591614Y-126890D03*
Y-116890D03*
Y-111890D03*
X-596614Y-106890D03*
Y-101890D03*
Y-111890D03*
X-591614Y-101890D03*
X-596614Y-116890D03*
X-591614Y-106890D03*
Y-86890D03*
Y-96890D03*
Y-91890D03*
X-596614Y-86890D03*
Y-91890D03*
Y-96890D03*
X-591614Y-81890D03*
Y-71890D03*
X-596614Y-76890D03*
Y-81890D03*
X-591614Y-76890D03*
X-596614Y-71890D03*
X-590000Y-25000D03*
Y-37500D03*
Y-12500D03*
Y0D03*
Y12500D03*
X-577500Y-177500D03*
Y-165000D03*
Y-152500D03*
Y-140000D03*
Y-127500D03*
Y-65000D03*
Y-37500D03*
Y-25000D03*
Y-12500D03*
Y0D03*
Y12500D03*
X-565000Y-165000D03*
Y-177500D03*
Y-152500D03*
Y-140000D03*
Y-65000D03*
Y-25000D03*
Y-37500D03*
Y-12500D03*
Y0D03*
Y12500D03*
X-540000Y-165000D03*
X-552500Y-177500D03*
X-540000D03*
X-552500Y-165000D03*
Y-152500D03*
X-540000D03*
Y-140000D03*
X-552500D03*
X-540000Y-127500D03*
Y-115000D03*
Y-102500D03*
Y-90000D03*
Y-77500D03*
Y-65000D03*
X-552500D03*
X-540000Y-25000D03*
X-552500Y-37500D03*
Y-25000D03*
X-540000Y-37500D03*
X-552500Y-12500D03*
X-540000D03*
Y0D03*
X-552500D03*
Y12500D03*
X-540000D03*
X-527500Y-177500D03*
Y-165000D03*
Y-152500D03*
Y-140000D03*
Y-127500D03*
Y-102500D03*
Y-115000D03*
Y-90000D03*
Y-77500D03*
Y-65000D03*
Y-37500D03*
Y-25000D03*
Y-12500D03*
Y0D03*
Y12500D03*
X-515000Y-165000D03*
Y-177500D03*
Y-152500D03*
Y-140000D03*
Y-127500D03*
Y-115000D03*
Y-102500D03*
Y-90000D03*
Y-77500D03*
Y-65000D03*
Y-25000D03*
Y-37500D03*
Y-12500D03*
Y0D03*
Y12500D03*
X-502500Y-102500D03*
X-490000D03*
Y-90000D03*
X-502500D03*
Y-77500D03*
X-490000D03*
X-502500Y-65000D03*
Y-37500D03*
X-490000D03*
X-502500Y-25000D03*
X-490000Y-12500D03*
Y0D03*
X-502500D03*
Y12500D03*
X-490000D03*
X-486421Y-26159D03*
X-477500Y-37500D03*
Y-25000D03*
Y0D03*
Y12500D03*
X-462000Y-73500D03*
X-465000Y-25000D03*
Y-37500D03*
X-461441Y6559D03*
X-465000Y12500D03*
X-453628Y-88300D03*
X-448128Y-88800D03*
X-456240Y-82020D03*
X-452700Y-69000D03*
X-449100Y-60841D03*
X-454421Y-26959D03*
X-443941Y6559D03*
X-449000Y6500D03*
X-448600Y-5900D03*
X-452500Y12500D03*
X-432118Y-87082D03*
X-436771Y-92400D03*
X-441959Y-74100D03*
X-429900Y-79600D03*
X-441959Y-68600D03*
X-429000Y-57600D03*
X-430700Y-63100D03*
X-441959D03*
Y-57600D03*
Y-41100D03*
Y-52100D03*
X-442000Y-29480D03*
X-441959Y-35600D03*
X-431000Y6500D03*
X-427500Y12500D03*
X-440000D03*
X-424600Y-14400D03*
X-413500Y12500D03*
X-405540Y-183080D03*
X-399435Y-183637D03*
X-396235D03*
X-401735Y-181337D03*
Y-185937D03*
X-405540Y-179630D03*
X-402559Y-177998D03*
X-401009Y-151780D03*
X-397809D03*
X-403309Y-149480D03*
Y-154080D03*
X-395509Y-149480D03*
Y-154080D03*
X-404134Y-157350D03*
X-402500Y12500D03*
X-379521Y-181100D03*
X-394188Y-181074D03*
X-393935Y-185937D03*
X-383661Y-177998D03*
X-393110D03*
X-394685Y-157350D03*
X-380421Y-147000D03*
X-391547Y-144435D03*
X-388347D03*
X-393847Y-146735D03*
X-393981Y-141950D03*
X-386047Y-142135D03*
Y-146735D03*
X-389600Y-123640D03*
X-389770Y-127220D03*
X-386500Y-44000D03*
Y-31500D03*
Y-19000D03*
X-390000Y12500D03*
X-375631Y-189905D03*
Y-186705D03*
X-365461Y-185380D03*
X-367761Y-183080D03*
Y-187680D03*
X-377931Y-184405D03*
Y-192205D03*
X-373331D03*
Y-184405D03*
X-377900Y-177933D03*
X-367913Y-179850D03*
X-364764Y-177998D03*
X-371063Y-178998D03*
X-374213Y-177998D03*
X-366339Y-157350D03*
X-375800Y-154000D03*
X-365514Y-136650D03*
X-373620Y-124430D03*
X-365514Y-132050D03*
X-374800Y-105700D03*
X-374000Y-56500D03*
Y-44000D03*
Y-19000D03*
X-365000Y12500D03*
X-377500D03*
X-362261Y-185380D03*
X-359961Y-183080D03*
Y-187680D03*
X-355315Y-177998D03*
X-350511Y-149900D03*
X-353711D03*
X-356011Y-152200D03*
X-348211D03*
X-356890Y-157350D03*
X-360014Y-134350D03*
X-363214D03*
X-357714Y-136650D03*
X-356011Y-147600D03*
X-348211D03*
X-357714Y-132050D03*
X-360500Y-87100D03*
X-353700Y-87600D03*
X-361500Y-56500D03*
X-348000Y-57000D03*
X-361500Y-44000D03*
X-348000D03*
X-361500Y-31500D03*
Y-19000D03*
X-348000D03*
X-352500Y12500D03*
X-333450Y-174950D03*
X-339341Y-167360D03*
X-336141D03*
X-341641Y-169660D03*
Y-165060D03*
X-333841D03*
Y-169660D03*
X-345866Y-177998D03*
X-347850Y-87050D03*
X-336000Y-53000D03*
Y-28000D03*
Y-15500D03*
X-340000Y12500D03*
X-321600Y-113500D03*
X-316500D03*
X-323500Y-65500D03*
X-321700Y-42000D03*
X-322400Y-31000D03*
X-321300Y-24950D03*
X-321800Y-7300D03*
X-321700Y-13628D03*
X-321859Y-1500D03*
X-327500Y12500D03*
X-312100Y-113500D03*
X-303200Y-43300D03*
Y-48800D03*
X-309400Y-47700D03*
X-302300Y-25950D03*
X-302900Y-37900D03*
X-309400Y-25100D03*
X-308500Y-36400D03*
X-308800Y-7400D03*
X-307900Y-13628D03*
X-302300Y-4450D03*
X-315000Y12500D03*
X-302500D03*
X-285000Y-107400D03*
Y-103100D03*
X-286500Y-113700D03*
X-296400Y-113500D03*
X-290400Y-43200D03*
X-290700Y-9750D03*
X-290300Y-4400D03*
X-290000Y12500D03*
X-274400Y-178200D03*
X-278100D03*
X-282300Y-113700D03*
X-277500Y12500D03*
X-254800Y-170650D03*
X-254800Y-175150D03*
X-265200Y-179850D03*
X-255672Y-157483D03*
Y-152883D03*
X-256496Y-147990D03*
Y-136730D03*
X-254721Y-129000D03*
X-254921Y-101700D03*
X-268000Y-13000D03*
X-255500D03*
Y-500D03*
X-265000Y12500D03*
X-237750Y-182300D03*
X-243250Y-182209D03*
X-244900Y-170700D03*
X-253372Y-155183D03*
X-250172D03*
X-247872Y-152883D03*
Y-157483D03*
X-247047Y-148090D03*
Y-136730D03*
X-238624Y-118455D03*
Y-121655D03*
X-240924Y-123960D03*
X-250321Y-129000D03*
X-244300Y-129300D03*
X-240300D03*
X-248622Y-101759D03*
X-242323Y-101600D03*
X-239222Y-104200D03*
X-240924Y-116160D03*
X-243000Y-40500D03*
Y-25500D03*
Y-13000D03*
Y-500D03*
X-240000Y12500D03*
X-252500D03*
X-226121Y-175150D03*
X-236900Y-170700D03*
X-237598Y-136730D03*
X-228150D03*
Y-148090D03*
X-237598D03*
X-236324Y-123960D03*
X-236024Y-102100D03*
X-236324Y-116160D03*
X-228932Y-104183D03*
X-230000Y-13500D03*
X-227500Y12500D03*
X-214500Y-179800D03*
X-215000Y12500D03*
X-196900Y-176500D03*
X-201600Y-176600D03*
X-206100D03*
X-202500Y12500D03*
X-185900Y-56200D03*
X-182900Y-29800D03*
X-179811Y-21300D03*
X-183200Y-4600D03*
X-179011Y4500D03*
X-177500Y12500D03*
X-190390Y12740D03*
X-163764Y-128576D03*
X-173800Y-47300D03*
X-173200Y-52400D03*
X-170200Y-34470D03*
X-170500Y-10000D03*
X-170300Y-16500D03*
X-165000Y12500D03*
X-150900Y-121100D03*
X-152400Y-125050D03*
X-145650Y-100550D03*
X-145100Y-74100D03*
X-152500Y12500D03*
X-138440Y-91390D03*
X-133301Y-86986D03*
X-142559Y-85886D03*
X-129882Y-90706D03*
X-129782Y-75998D03*
X-138640D03*
X-142559Y-70873D03*
X-133701Y-56060D03*
X-129782Y-60885D03*
X-142559Y-56060D03*
X-142130Y-41290D03*
X-139000Y-8500D03*
Y-21000D03*
X-140000Y12500D03*
X-127500D03*
X-126600Y-75410D03*
X-124590Y-41500D03*
X-114000Y-33500D03*
X-126500Y-21000D03*
X-114000Y-8500D03*
Y-21000D03*
X-115000Y12500D03*
X-99252Y-100849D03*
Y-85886D03*
X-101700Y-73800D03*
X-101500Y-33500D03*
Y-21000D03*
Y-8500D03*
X-102500Y12500D03*
X-95433Y-90706D03*
X-86575D03*
X-90194Y-101049D03*
X-83310Y-75360D03*
X-95333Y-75848D03*
X-86475D03*
Y-60885D03*
X-87700Y-57700D03*
X-95333Y-45922D03*
X-86475D03*
X-89000Y-8500D03*
Y-21000D03*
X-90000Y12500D03*
X-74921Y-171500D03*
X-71500Y-158500D03*
Y-146000D03*
Y-133500D03*
X-71700Y-121000D03*
X-70500Y-108600D03*
X-76500Y-33500D03*
Y-21000D03*
Y-8500D03*
X-77500Y12500D03*
X-65000D03*
X-59500Y-173500D03*
Y-161000D03*
Y-136000D03*
Y-148500D03*
Y-123500D03*
Y-96000D03*
Y-83500D03*
Y-71000D03*
Y-46000D03*
Y-33500D03*
Y-8500D03*
X-54500Y1500D03*
X-52500Y12500D03*
X-42500Y-173500D03*
X-43000Y-158500D03*
Y-146000D03*
X-47000Y-71000D03*
X-34500D03*
X-47000Y-83500D03*
X-34500Y-58500D03*
X-47000D03*
Y-46000D03*
X-34500D03*
Y-33500D03*
X-47000D03*
Y-21000D03*
X-34500Y-8500D03*
X-47000D03*
X-34500Y-21000D03*
X-42000Y1500D03*
X-40000Y12500D03*
X-18000Y-173500D03*
Y-158500D03*
X-30500D03*
Y-146000D03*
X-18000D03*
X-21150Y-83600D03*
X-22000Y-71000D03*
Y-58500D03*
Y-46000D03*
Y-33500D03*
Y-21000D03*
Y-8500D03*
X-27500Y12500D03*
X-9500Y-120000D03*
Y-108500D03*
Y-96000D03*
X-9350Y-83500D03*
X-9500Y-71000D03*
Y-46000D03*
Y-33500D03*
Y-8500D03*
Y-21000D03*
X-17000Y1500D03*
X-2500Y12500D03*
X-15000D03*
X3000Y-120000D03*
Y-108500D03*
Y-83500D03*
Y-71000D03*
Y-58500D03*
Y-46000D03*
Y-33500D03*
Y-21000D03*
Y-8500D03*
G54D32*
G01X-1181990Y-545833D02*
X-1181410Y-545208D01*
X-1180975Y-544167D01*
X-1180685Y-542708D01*
X-1180975Y-541458D01*
X-1181555Y-540625D01*
X-1182570Y-540000D01*
X-1186485D01*
Y-552500D01*
X-1181700D01*
X-1180685Y-551667D01*
X-1180105Y-550417D01*
X-1179815Y-548958D01*
X-1180105Y-547500D01*
X-1180975Y-546250D01*
X-1181990Y-545833D01*
X-1186485D01*
G01X-1171350Y-552500D02*
X-1172510Y-552292D01*
X-1173525Y-551459D01*
X-1174395Y-550208D01*
X-1174975Y-548750D01*
X-1175265Y-547083D01*
Y-545417D01*
X-1174975Y-543750D01*
X-1174395Y-542292D01*
X-1173525Y-541042D01*
X-1172510Y-540208D01*
X-1171350Y-540000D01*
X-1170190Y-540208D01*
X-1169175Y-541042D01*
X-1168305Y-542292D01*
X-1167725Y-543750D01*
X-1167435Y-545417D01*
Y-547083D01*
X-1167725Y-548750D01*
X-1168305Y-550208D01*
X-1169175Y-551459D01*
X-1170190Y-552292D01*
X-1171350Y-552500D01*
G01X-1159550Y-540000D02*
Y-552500D01*
G01X-1162885Y-540000D02*
X-1156215D01*
G01X-1147750D02*
Y-552500D01*
G01X-1151085Y-540000D02*
X-1144415D01*
G01X-1135950Y-552500D02*
X-1137110Y-552292D01*
X-1138125Y-551459D01*
X-1138995Y-550208D01*
X-1139575Y-548750D01*
X-1139865Y-547083D01*
Y-545417D01*
X-1139575Y-543750D01*
X-1138995Y-542292D01*
X-1138125Y-541042D01*
X-1137110Y-540208D01*
X-1135950Y-540000D01*
X-1134790Y-540208D01*
X-1133775Y-541042D01*
X-1132905Y-542292D01*
X-1132325Y-543750D01*
X-1132035Y-545417D01*
Y-547083D01*
X-1132325Y-548750D01*
X-1132905Y-550208D01*
X-1133775Y-551459D01*
X-1134790Y-552292D01*
X-1135950Y-552500D01*
G01X-1127920D02*
Y-540000D01*
X-1124150Y-550417D01*
X-1120380Y-540000D01*
Y-552500D01*
G01X-1103595Y-550834D02*
X-1102435Y-551875D01*
X-1101130Y-552500D01*
X-1099970D01*
X-1098810Y-551875D01*
X-1097940Y-550834D01*
X-1097505Y-549375D01*
X-1097795Y-547917D01*
X-1098520Y-546667D01*
X-1099825Y-545833D01*
X-1101565Y-545417D01*
X-1102580Y-544584D01*
X-1103015Y-543125D01*
X-1102725Y-541667D01*
X-1102000Y-540625D01*
X-1100985Y-540000D01*
X-1099970D01*
X-1098955Y-540417D01*
X-1098085Y-541458D01*
G01X-1090490Y-540000D02*
X-1087010D01*
G01X-1088750D02*
Y-552500D01*
G01X-1090490D02*
X-1087010D01*
G01X-1080140D02*
Y-540000D01*
X-1077240D01*
X-1076080Y-540625D01*
X-1075210Y-541458D01*
X-1074485Y-542708D01*
X-1073905Y-544167D01*
X-1073760Y-546250D01*
X-1073905Y-548333D01*
X-1074485Y-549792D01*
X-1075210Y-551042D01*
X-1076080Y-551875D01*
X-1077240Y-552500D01*
X-1080140D01*
G01X-1062250D02*
X-1068050D01*
Y-540000D01*
X-1062250D01*
G01X-1064570Y-546042D02*
X-1068050D01*
G01X-1053640Y-554792D02*
X-1053060Y-552083D01*
G01X-1032650Y-540000D02*
Y-552500D01*
X-1026850D01*
G01X-1021575D02*
X-1017950Y-540000D01*
X-1014325Y-552500D01*
G01X-1015630Y-548125D02*
X-1020270D01*
G01X-1006150Y-552500D02*
Y-546875D01*
X-1009050Y-540000D01*
G01X-1003250D02*
X-1006150Y-546875D01*
G01X-991450Y-552500D02*
X-997250D01*
Y-540000D01*
X-991450D01*
G01X-993770Y-546042D02*
X-997250D01*
G01X-985450Y-552500D02*
Y-540000D01*
X-981825D01*
X-980665Y-540625D01*
X-979940Y-541458D01*
X-979650Y-543125D01*
X-979940Y-544792D01*
X-980810Y-545833D01*
X-981825Y-546458D01*
X-985450D01*
G01X-981825D02*
X-979650Y-552500D01*
G01X-958950D02*
X-957935Y-552292D01*
X-956775Y-551667D01*
X-956050Y-550625D01*
X-955760Y-549167D01*
X-956050Y-547709D01*
X-956920Y-546458D01*
X-958225Y-545833D01*
X-959675D01*
X-960545Y-545417D01*
X-961270Y-544375D01*
X-961560Y-542917D01*
X-961125Y-541458D01*
X-960110Y-540417D01*
X-958950Y-540000D01*
X-957790Y-540417D01*
X-956775Y-541458D01*
X-956340Y-542917D01*
X-956630Y-544375D01*
X-957355Y-545417D01*
X-958225Y-545833D01*
X-959675D01*
X-960980Y-546458D01*
X-961850Y-547709D01*
X-962140Y-549167D01*
X-961850Y-550625D01*
X-961125Y-551667D01*
X-959965Y-552292D01*
X-958950Y-552500D01*
G54D23*
X-1282480Y-172283D03*
Y-130157D03*
Y-94724D03*
Y-59291D03*
Y-23858D03*
X-1253740Y-184094D03*
X-1225394D03*
X-1207677Y-154567D03*
Y-112441D03*
Y-77008D03*
Y-41575D03*
Y-6142D03*
X-412402Y-172283D03*
Y-130157D03*
Y-94724D03*
Y-59291D03*
Y-23858D03*
X-383661Y-184094D03*
X-355315D03*
X-337598Y-154567D03*
Y-112441D03*
Y-77008D03*
Y-41575D03*
Y-6142D03*
G54D14*
X-1646000Y-140700D03*
X-836000Y-172000D03*
Y500D03*
X-28500Y-169500D03*
Y500D03*
G54D33*
G01X-1652043Y-124543D02*
X-1649000Y-121500D01*
G01D02*
X-1645957Y-118457D01*
G01X-1652043D02*
X-1649000Y-121500D01*
G01D02*
X-1645957Y-124543D01*
G01X-1185925Y-592500D02*
X-1178575Y-577500D01*
G01X-1185925D02*
X-1178575Y-592500D01*
G01X-1168050D02*
X-1166825Y-592250D01*
X-1165425Y-591500D01*
X-1164550Y-590250D01*
X-1164200Y-588500D01*
X-1164550Y-586750D01*
X-1165600Y-585250D01*
X-1167175Y-584500D01*
X-1168925D01*
X-1169975Y-584000D01*
X-1170850Y-582750D01*
X-1171200Y-581000D01*
X-1170675Y-579250D01*
X-1169450Y-578000D01*
X-1168050Y-577500D01*
X-1166650Y-578000D01*
X-1165425Y-579250D01*
X-1164900Y-581000D01*
X-1165250Y-582750D01*
X-1166125Y-584000D01*
X-1167175Y-584500D01*
X-1168925D01*
X-1170500Y-585250D01*
X-1171550Y-586750D01*
X-1171900Y-588500D01*
X-1171550Y-590250D01*
X-1170675Y-591500D01*
X-1169275Y-592250D01*
X-1168050Y-592500D01*
G01X-1153850D02*
X-1152625Y-592250D01*
X-1151225Y-591500D01*
X-1150350Y-590250D01*
X-1150000Y-588500D01*
X-1150350Y-586750D01*
X-1151400Y-585250D01*
X-1152975Y-584500D01*
X-1154725D01*
X-1155775Y-584000D01*
X-1156650Y-582750D01*
X-1157000Y-581000D01*
X-1156475Y-579250D01*
X-1155250Y-578000D01*
X-1153850Y-577500D01*
X-1152450Y-578000D01*
X-1151225Y-579250D01*
X-1150700Y-581000D01*
X-1151050Y-582750D01*
X-1151925Y-584000D01*
X-1152975Y-584500D01*
X-1154725D01*
X-1156300Y-585250D01*
X-1157350Y-586750D01*
X-1157700Y-588500D01*
X-1157350Y-590250D01*
X-1156475Y-591500D01*
X-1155075Y-592250D01*
X-1153850Y-592500D01*
G01X-1140000D02*
X-1139650Y-589250D01*
X-1139125Y-586500D01*
X-1138425Y-584000D01*
X-1137550Y-581250D01*
X-1136150Y-577500D01*
X-1143150D01*
G01X-1129300Y-590250D02*
X-1128250Y-591500D01*
X-1127025Y-592250D01*
X-1125450Y-592500D01*
X-1123875Y-592000D01*
X-1122650Y-591000D01*
X-1121775Y-589250D01*
X-1121600Y-587250D01*
X-1121950Y-585250D01*
X-1122825Y-584000D01*
X-1124050Y-583000D01*
X-1125275Y-582750D01*
X-1126500Y-583000D01*
X-1128075Y-584000D01*
X-1127550Y-577500D01*
X-1122825D01*
G01X-1111600Y-592500D02*
X-1111250Y-589250D01*
X-1110725Y-586500D01*
X-1110025Y-584000D01*
X-1109150Y-581250D01*
X-1107750Y-577500D01*
X-1114750D01*
G01X-1097050Y-592500D02*
Y-577500D01*
X-1099150Y-580500D01*
G01Y-592500D02*
X-1094950D01*
G01X-1085125Y-587500D02*
X-1080575D01*
G01X-1068650Y-577500D02*
X-1070050Y-578000D01*
X-1071100Y-579250D01*
X-1071800Y-580750D01*
X-1072325Y-582750D01*
X-1072500Y-585000D01*
X-1072325Y-587250D01*
X-1071800Y-589250D01*
X-1071100Y-590750D01*
X-1070050Y-592000D01*
X-1068650Y-592500D01*
X-1067250Y-592000D01*
X-1066200Y-590750D01*
X-1065500Y-589250D01*
X-1064975Y-587250D01*
X-1064800Y-585000D01*
X-1064975Y-582750D01*
X-1065500Y-580750D01*
X-1066200Y-579250D01*
X-1067250Y-578000D01*
X-1068650Y-577500D01*
G01X-1054450D02*
X-1055850Y-578000D01*
X-1056900Y-579250D01*
X-1057600Y-580750D01*
X-1058125Y-582750D01*
X-1058300Y-585000D01*
X-1058125Y-587250D01*
X-1057600Y-589250D01*
X-1056900Y-590750D01*
X-1055850Y-592000D01*
X-1054450Y-592500D01*
X-1053050Y-592000D01*
X-1052000Y-590750D01*
X-1051300Y-589250D01*
X-1050775Y-587250D01*
X-1050600Y-585000D01*
X-1050775Y-582750D01*
X-1051300Y-580750D01*
X-1052000Y-579250D01*
X-1053050Y-578000D01*
X-1054450Y-577500D01*
G01X-1044100Y-590250D02*
X-1043050Y-591500D01*
X-1041825Y-592250D01*
X-1040250Y-592500D01*
X-1038675Y-592000D01*
X-1037450Y-591000D01*
X-1036575Y-589250D01*
X-1036400Y-587250D01*
X-1036750Y-585250D01*
X-1037625Y-584000D01*
X-1038850Y-583000D01*
X-1040075Y-582750D01*
X-1041300Y-583000D01*
X-1042875Y-584000D01*
X-1042350Y-577500D01*
X-1037625D01*
G01X-911875Y-592500D02*
X-907500Y-577500D01*
X-903125Y-592500D01*
G01X-904700Y-587250D02*
X-910300D01*
G01X-810781Y-87027D02*
X-806854Y-83100D01*
G01D02*
X-802927Y-79173D01*
G01X-810781D02*
X-806854Y-83100D01*
G01D02*
X-802927Y-87027D01*
G01X-796771Y-164893D02*
X-793728Y-161850D01*
G01D02*
X-790685Y-164893D01*
G01X-793728Y-161850D02*
X-790685Y-158807D01*
G01X-796771D02*
X-793728Y-161850D01*
G01X-790400Y-88300D02*
X-785200Y-83100D01*
G01X-790400Y-77900D02*
X-785200Y-83100D01*
G01D02*
X-780000Y-88300D01*
G01X-785200Y-83100D02*
X-780000Y-77900D01*
G54D24*
X-1141240Y-132520D03*
Y-112835D03*
Y-94331D03*
X-1132087Y-150630D03*
X-1113189D03*
X-1094291D03*
X-1085138Y-132520D03*
Y-112835D03*
Y-94331D03*
X-271161Y-132520D03*
Y-112835D03*
Y-94331D03*
X-262008Y-150630D03*
X-243110D03*
X-224213D03*
X-215059Y-132520D03*
Y-112835D03*
Y-94331D03*
G54D15*
X-1649000Y-121500D03*
Y-105752D03*
Y-113626D03*
Y-97878D03*
X-1327756Y-175039D03*
Y-167165D03*
Y-159291D03*
Y-143543D03*
Y-135669D03*
X-1319882Y-175039D03*
Y-167165D03*
Y-159291D03*
Y-143543D03*
Y-135669D03*
Y-127795D03*
X-1296260Y-175039D03*
X-1304134D03*
X-1296260Y-167165D03*
X-1304134D03*
X-1296260Y-159291D03*
X-1304134D03*
X-1296260Y-143543D03*
X-1304134D03*
X-1296260Y-135669D03*
X-1304134D03*
X-1296260Y-127795D03*
X-1304134D03*
X-793728Y-161850D03*
Y-153976D03*
Y-138228D03*
Y-146102D03*
X-457677Y-175039D03*
Y-167165D03*
Y-159291D03*
Y-143543D03*
Y-135669D03*
X-449803Y-175039D03*
Y-167165D03*
Y-159291D03*
Y-143543D03*
Y-135669D03*
Y-127795D03*
X-426181Y-175039D03*
X-434055D03*
X-426181Y-167165D03*
X-434055D03*
X-426181Y-159291D03*
X-434055D03*
X-426181Y-143543D03*
X-434055D03*
X-426181Y-135669D03*
X-434055D03*
X-426181Y-127795D03*
X-434055D03*
G54D34*
G01X-1644488Y-27500D02*
Y7244D01*
G01X-1654488Y-27300D02*
Y7244D01*
G01X-1649488D02*
Y-27400D01*
G01X-1639488Y7244D02*
Y-27500D01*
G01X-1634488Y-27600D02*
Y7244D01*
G01X-1629488Y-27700D02*
Y7244D01*
G01X-1452000Y-74000D02*
X-1446800D01*
X-1440900Y-68100D01*
X-1347300D01*
X-1323400Y-92000D01*
X-1288900D01*
X-1286960Y-90060D01*
X-1271036D01*
X-1268630Y-92466D01*
Y-92470D01*
X-1264300Y-96800D01*
X-1205400D01*
X-1190300Y-111900D01*
X-1168200D01*
X-1165600Y-114500D01*
Y-117400D01*
G01X-1321000Y-94850D02*
X-1321100Y-94950D01*
X-1323850D01*
X-1348310Y-70490D01*
X-1437990D01*
X-1445700Y-78200D01*
X-1452000D01*
G01X-1452100Y-82200D02*
X-1445200D01*
X-1436000Y-73000D01*
X-1349200D01*
X-1322700Y-99500D01*
X-1313300D01*
X-1310000Y-102800D01*
X-1207000D01*
X-1195000Y-114800D01*
X-1176100D01*
G01X-448600Y-5900D02*
X-455400D01*
X-465800Y4500D01*
X-608500D01*
X-613700Y9700D01*
X-1279500D01*
X-1349800Y-60600D01*
X-1441700D01*
X-1447000Y-65900D01*
X-1451500D01*
X-1451700Y-65700D01*
G01X-299800Y-118500D02*
Y-115750D01*
X-303890Y-111660D01*
X-313960D01*
X-322620Y-103000D01*
X-396700D01*
X-409869Y-89831D01*
X-418669D01*
X-420000Y-88500D01*
X-426500D01*
X-428000Y-90000D01*
X-434300D01*
X-436800Y-87500D01*
Y-12000D01*
X-457600Y8800D01*
X-607800D01*
X-610700Y11700D01*
X-1280810D01*
X-1350910Y-58400D01*
X-1443200D01*
X-1446800Y-62000D01*
X-1451300D01*
X-1451500Y-61800D01*
G01X-321600Y-113500D02*
X-323500D01*
X-329300Y-107700D01*
X-368999D01*
X-370216Y-108917D01*
X-436183D01*
X-459300Y-85800D01*
Y-80600D01*
X-457800Y-79100D01*
Y-13400D01*
X-467650Y-3550D01*
X-604850D01*
X-616100Y7700D01*
X-1278370D01*
X-1325500Y-39430D01*
Y-43600D01*
X-1347380Y-65480D01*
X-1442380D01*
X-1446500Y-69600D01*
X-1451800D01*
G01X-1160000Y-115100D02*
X-1164210Y-110890D01*
X-1189710D01*
X-1204800Y-95800D01*
X-1263700D01*
X-1270460Y-89040D01*
X-1288480D01*
X-1289940Y-90500D01*
X-1309500D01*
X-1310000Y-91000D01*
X-1322900D01*
X-1347100Y-66800D01*
X-1441300D01*
X-1446300Y-71800D01*
X-1449100D01*
G01X-1448900Y-76100D02*
X-1445800D01*
X-1438900Y-69200D01*
X-1348100D01*
X-1324300Y-93000D01*
X-1312000D01*
X-1310000Y-95000D01*
X-1306850D01*
G01X-1170300Y-114600D02*
X-1172840D01*
X-1173795Y-112950D01*
X-1195150D01*
X-1206700Y-101400D01*
X-1309700D01*
X-1314100Y-97000D01*
X-1323400D01*
X-1348600Y-71800D01*
X-1436800D01*
X-1445300Y-80300D01*
X-1449000D01*
G01X-1448800Y-63800D02*
X-1448600Y-64000D01*
X-1446800D01*
X-1442300Y-59500D01*
X-1350300D01*
X-1280100Y10700D01*
X-612200D01*
X-608000Y6500D01*
X-465300D01*
X-456550Y-2250D01*
X-448850D01*
X-438800Y-12300D01*
Y-90371D01*
X-436771Y-92400D01*
G01X-296400Y-113500D02*
X-296700D01*
X-299640Y-110560D01*
X-313140D01*
X-321900Y-101800D01*
X-395000D01*
X-408300Y-88500D01*
X-418500D01*
X-420000Y-87000D01*
X-428000D01*
X-430000Y-89000D01*
X-433300D01*
X-435200Y-87100D01*
Y-10900D01*
X-456100Y10000D01*
X-607000D01*
X-609700Y12700D01*
X-1281500D01*
X-1351600Y-57400D01*
X-1444800D01*
X-1447500Y-60100D01*
X-1448500D01*
X-1448700Y-59900D01*
G01X-316500Y-113500D02*
X-317700D01*
X-325000Y-106200D01*
X-370404D01*
X-371876Y-107672D01*
X-432728D01*
X-450900Y-89500D01*
Y-86000D01*
X-452200Y-84700D01*
Y-82200D01*
X-455200Y-79200D01*
Y-33300D01*
X-451800Y-29900D01*
Y-12600D01*
X-467100Y2700D01*
X-609000D01*
X-615000Y8700D01*
X-1278990D01*
X-1326610Y-38920D01*
Y-42710D01*
X-1348280Y-64380D01*
X-1443280D01*
X-1446500Y-67600D01*
X-1448700D01*
X-1448800Y-67700D01*
G01X-1202100Y-103200D02*
X-1205600Y-99700D01*
X-1309800D01*
X-1314650Y-94850D01*
X-1321000D01*
G01X-1154200Y-103100D02*
X-1159780Y-108680D01*
X-1188520D01*
X-1203600Y-93600D01*
X-1261900D01*
X-1268700Y-86800D01*
X-1297900D01*
X-1300600Y-84100D01*
X-1302400D01*
G01X-1154400Y-107900D02*
X-1156230Y-109730D01*
X-1189370D01*
X-1204300Y-94800D01*
X-1262700D01*
X-1269600Y-87900D01*
X-1290290D01*
X-1290890Y-88500D01*
X-1300350D01*
G01X-1237992Y-179850D02*
X-1238150Y-179692D01*
Y-177520D01*
X-1239540Y-176130D01*
X-1256920D01*
X-1259310Y-178520D01*
Y-186770D01*
X-1261460Y-188920D01*
X-1273290D01*
X-1276940Y-185270D01*
Y-181800D01*
X-1278161Y-180579D01*
X-1279429D01*
G01X-1200000Y-560000D02*
X-890000D01*
G01Y-520000D02*
X-1200000D01*
G01X-575000Y-480000D02*
X-1200000D01*
G01X-1165600Y-117400D02*
X-1171100Y-122900D01*
Y-131300D01*
X-1169800Y-132600D01*
Y-141926D01*
X-1173386Y-145512D01*
G01X-1017670Y-123250D02*
X-1026770Y-132350D01*
X-1034276D01*
X-1037500Y-129126D01*
Y-115000D01*
X-1045000Y-107500D01*
X-1088400D01*
X-1097400Y-98500D01*
X-1128700D01*
X-1137800Y-89400D01*
X-1144400D01*
X-1148500Y-93500D01*
Y-107800D01*
X-1158100Y-117400D01*
X-1165600D01*
G01X-1160000Y-115100D02*
X-1156000Y-111100D01*
X-1153800D01*
X-1150000Y-107300D01*
Y-93300D01*
X-1144800Y-88100D01*
X-1136600D01*
X-1127700Y-97000D01*
X-1096900D01*
X-1087900Y-106000D01*
X-1044500D01*
X-1036046Y-114454D01*
Y-129047D01*
X-1034000Y-131093D01*
X-1030273D01*
X-1022140Y-122960D01*
G01X-1154400Y-107900D02*
X-1151400Y-104900D01*
Y-93200D01*
X-1145300Y-87100D01*
X-1135200D01*
X-1126400Y-95900D01*
X-1096200D01*
X-1087100Y-105000D01*
X-1043000D01*
X-1034000Y-114000D01*
Y-128419D01*
X-1033843Y-128576D01*
G01X-927500Y-560000D02*
Y-600000D01*
G01X-915000Y-440000D02*
Y-480000D01*
G01X-890000D02*
Y-600000D01*
G01X-870000Y-440000D02*
Y-480000D01*
G01X-591200Y-179700D02*
X-603500D01*
X-609200Y-174000D01*
X-622100D01*
X-630450Y-182350D01*
X-725150D01*
X-726800Y-180700D01*
Y-137700D01*
X-730012Y-134488D01*
X-730157D01*
G01X-680000Y-480000D02*
Y-440000D01*
G01X-374800Y-105700D02*
X-410600D01*
X-416700Y-99600D01*
X-433100D01*
X-448600Y-84100D01*
Y-68600D01*
X-452100Y-65100D01*
Y-58000D01*
X-448600Y-54500D01*
Y-5900D01*
G01X-286500Y-113700D02*
X-291500D01*
X-295700Y-109500D01*
X-312540D01*
X-321740Y-100300D01*
X-394300D01*
X-407395Y-87205D01*
X-418066D01*
X-419500Y-85771D01*
X-428771D01*
X-430082Y-87082D01*
X-432118D01*
G01X-429900Y-79600D02*
X-412100D01*
X-392900Y-98800D01*
X-321500D01*
X-311890Y-108410D01*
X-293090D01*
X-290500Y-111000D01*
X-285000D01*
X-282300Y-113700D01*
G01X-374800Y-105700D02*
X-373800Y-104700D01*
X-322720D01*
X-313920Y-113500D01*
X-312100D01*
G01X-274400Y-178200D02*
Y-178100D01*
X-276200Y-176300D01*
X-278800D01*
X-284930Y-182430D01*
X-296670D01*
X-298800Y-180300D01*
Y-161043D01*
X-303307Y-156535D01*
G01X-278100Y-178200D02*
Y-179800D01*
X-281750Y-183450D01*
X-297350D01*
X-300000Y-180800D01*
Y-165354D01*
X-303307Y-162047D01*
G01X-299800Y-118500D02*
Y-144712D01*
X-300600Y-145512D01*
X-303307D01*
G01X-150900Y-121100D02*
Y-122800D01*
X-149500Y-124200D01*
Y-127200D01*
X-158000Y-135700D01*
X-164900D01*
X-168900Y-131700D01*
Y-115700D01*
X-176900Y-107700D01*
X-220900D01*
X-230100Y-98500D01*
X-260600D01*
X-269500Y-89600D01*
X-274600D01*
X-277500Y-92500D01*
Y-118000D01*
X-280400Y-120900D01*
X-297400D01*
X-299800Y-118500D01*
G01X-152400Y-125050D02*
X-159550Y-132200D01*
X-164300D01*
X-166400Y-130100D01*
Y-114100D01*
X-174700Y-105800D01*
X-219100D01*
X-228500Y-96400D01*
X-260400D01*
X-269100Y-87700D01*
X-275000D01*
X-278900Y-91600D01*
Y-116900D01*
X-281000Y-119000D01*
X-291000D01*
X-296400Y-113600D01*
Y-113500D01*
G01X-163764Y-128576D02*
X-163700Y-128512D01*
Y-113600D01*
X-173300Y-104000D01*
X-216900D01*
X-226200Y-94700D01*
X-259600D01*
X-268300Y-86000D01*
X-276600D01*
X-280300Y-89700D01*
Y-115000D01*
X-281800Y-116500D01*
X-283700D01*
X-286500Y-113700D01*
G01X-1200000Y-600000D02*
X-575000D01*
Y-440000D01*
X-1200000D01*
Y-600000D01*
G54D25*
X-1141240Y-142362D03*
Y-102992D03*
Y-63622D03*
Y-24252D03*
X-1128760Y-83307D03*
X-1118917Y-4567D03*
X-1107500Y-83307D03*
X-1085138Y-122677D03*
Y-83307D03*
Y-43937D03*
Y-4567D03*
X-785200Y-83100D03*
X-271161Y-142362D03*
Y-102992D03*
Y-63622D03*
Y-24252D03*
X-258681Y-83307D03*
X-237421D03*
X-248839Y-4567D03*
X-215059Y-122677D03*
Y-83307D03*
Y-43937D03*
Y-4567D03*
G54D16*
X-1654488Y7244D03*
X-1649488D03*
X-1644488D03*
X-1639488D03*
X-1634488D03*
X-1629488D03*
G54D35*
G01X-1649000Y-113626D02*
X-1652337Y-110289D01*
X-1654992D01*
X-1657700Y-112997D01*
Y-113897D01*
X-1657000Y-114597D01*
Y-116497D01*
X-1657700Y-117197D01*
Y-125300D01*
X-1652800Y-130200D01*
X-1651900D01*
X-1651200Y-129500D01*
X-1649500D01*
X-1648800Y-130200D01*
X-1646848D01*
X-1646148Y-129500D01*
X-1644648D01*
X-1643948Y-130200D01*
X-1642803D01*
X-1641196Y-131807D01*
X-1640293D01*
X-1638991Y-133109D01*
Y-134012D01*
X-1634699Y-138304D01*
Y-140168D01*
X-1633999Y-140868D01*
Y-142568D01*
X-1634699Y-143268D01*
Y-148104D01*
X-1625400Y-157403D01*
Y-158421D01*
X-1624700Y-159121D01*
Y-161221D01*
X-1625400Y-161921D01*
Y-164890D01*
X-1624297Y-165993D01*
X-1623407D01*
X-1621805Y-167595D01*
Y-168485D01*
X-1620575Y-169715D01*
X-1618140D01*
X-1615984Y-167559D01*
G01X-1649000Y-105752D02*
X-1652337Y-109089D01*
X-1655489D01*
X-1658900Y-112500D01*
Y-125797D01*
X-1653297Y-131400D01*
X-1643300D01*
X-1635899Y-138801D01*
Y-148601D01*
X-1626600Y-157900D01*
Y-165387D01*
X-1621072Y-170915D01*
X-1618140D01*
X-1615984Y-173071D01*
G01X-1608110Y-139606D02*
X-1605954Y-141762D01*
X-1605454D01*
X-1604800Y-141108D01*
Y-94200D01*
X-1604736Y-94136D01*
Y-94041D01*
X-1602100Y-91406D01*
X-1602006D01*
X-1572900Y-62300D01*
X-1521203D01*
X-1499723Y-83780D01*
X-1485927D01*
X-1484840Y-82693D01*
Y-80360D01*
X-1483250Y-78770D01*
X-1480060D01*
X-1478550Y-80280D01*
Y-82703D01*
X-1477463Y-83790D01*
X-1473593D01*
X-1471693Y-81890D01*
G01X-1608110Y-145118D02*
X-1605954Y-142962D01*
X-1604957D01*
X-1603600Y-141605D01*
Y-94697D01*
X-1603536Y-94633D01*
Y-94538D01*
X-1601603Y-92606D01*
X-1601508D01*
X-1572403Y-63500D01*
X-1521700D01*
X-1500220Y-84980D01*
X-1485430D01*
X-1483640Y-83190D01*
Y-80857D01*
X-1482753Y-79970D01*
X-1480557D01*
X-1479750Y-80777D01*
Y-83200D01*
X-1477960Y-84990D01*
X-1473593D01*
X-1471693Y-86890D01*
G01X-1476693Y-91890D02*
X-1478593Y-93790D01*
X-1482970D01*
X-1483550Y-93210D01*
Y-90400D01*
X-1485140Y-88810D01*
X-1493440D01*
X-1496820Y-92190D01*
X-1500913D01*
X-1526003Y-67100D01*
X-1570400D01*
X-1596900Y-93600D01*
Y-119428D01*
X-1597580Y-120109D01*
X-1598080D01*
X-1600236Y-117953D01*
G01X-1476693Y-96890D02*
X-1478593Y-94990D01*
X-1483467D01*
X-1484750Y-93707D01*
Y-90897D01*
X-1485637Y-90010D01*
X-1492943D01*
X-1496323Y-93390D01*
X-1501410D01*
X-1526500Y-68300D01*
X-1569903D01*
X-1595700Y-94097D01*
Y-119925D01*
X-1597083Y-121309D01*
X-1598080D01*
X-1600236Y-123465D01*
G01X-1471693Y-101890D02*
X-1473593Y-103790D01*
X-1477970D01*
X-1478550Y-103210D01*
Y-100400D01*
X-1480140Y-98810D01*
X-1502393D01*
X-1529303Y-71900D01*
X-1567700D01*
X-1589000Y-93200D01*
Y-124850D01*
X-1589377Y-125227D01*
X-1590206D01*
X-1592362Y-123071D01*
G01X-1584488Y-117953D02*
X-1582332Y-120109D01*
X-1581832D01*
X-1581114Y-119391D01*
Y-99159D01*
X-1581100Y-99145D01*
Y-94000D01*
X-1563900Y-76800D01*
X-1531703D01*
X-1502223Y-106280D01*
X-1492070D01*
X-1489540Y-108810D01*
X-1485140D01*
X-1483550Y-110400D01*
Y-113210D01*
X-1482970Y-113790D01*
X-1478593D01*
X-1476693Y-111890D01*
G01X-1471693Y-106890D02*
X-1473593Y-104990D01*
X-1478467D01*
X-1479750Y-103707D01*
Y-100897D01*
X-1480637Y-100010D01*
X-1502890D01*
X-1529800Y-73100D01*
X-1567203D01*
X-1587800Y-93697D01*
Y-125347D01*
X-1588880Y-126427D01*
X-1590206D01*
X-1592362Y-128583D01*
G01X-1584488Y-123465D02*
X-1582332Y-121309D01*
X-1581335D01*
X-1579914Y-119888D01*
Y-99656D01*
X-1579900Y-99642D01*
Y-94497D01*
X-1563403Y-78000D01*
X-1532200D01*
X-1502720Y-107480D01*
X-1492567D01*
X-1490037Y-110010D01*
X-1485637D01*
X-1484750Y-110897D01*
Y-113707D01*
X-1483467Y-114990D01*
X-1478593D01*
X-1476693Y-116890D01*
G01X-1471693Y-121890D02*
X-1473593Y-123790D01*
X-1477970D01*
X-1478550Y-123210D01*
Y-120400D01*
X-1480140Y-118810D01*
X-1500793D01*
X-1511900Y-107703D01*
Y-105003D01*
X-1535103Y-81800D01*
X-1535115D01*
X-1535115Y-81799D01*
X-1539090D01*
X-1539091Y-81800D01*
X-1561500D01*
X-1572597Y-92897D01*
X-1573300Y-93600D01*
X-1573300Y-94594D01*
X-1573300Y-124569D01*
X-1573958Y-125227D01*
X-1574458D01*
X-1576614Y-123071D01*
G01X-1568740Y-117953D02*
X-1566584Y-120109D01*
X-1566150D01*
X-1565400Y-119358D01*
Y-94700D01*
X-1557300Y-86600D01*
X-1538700D01*
X-1521600Y-103700D01*
Y-107500D01*
X-1502800Y-126300D01*
X-1494120D01*
X-1491610Y-128810D01*
X-1485140D01*
X-1483550Y-130400D01*
Y-133210D01*
X-1482970Y-133790D01*
X-1478593D01*
X-1476693Y-131890D01*
G01X-1471693Y-126890D02*
X-1473593Y-124990D01*
X-1478467D01*
X-1479750Y-123707D01*
Y-120897D01*
X-1480637Y-120010D01*
X-1501290D01*
X-1513100Y-108200D01*
Y-105500D01*
X-1535600Y-83000D01*
X-1535612D01*
X-1535612Y-82999D01*
X-1538593D01*
X-1538594Y-83000D01*
X-1561003D01*
X-1572100Y-94097D01*
Y-125066D01*
X-1573461Y-126427D01*
X-1574458D01*
X-1576614Y-128583D01*
G01X-1568740Y-123465D02*
X-1566584Y-121309D01*
X-1565653D01*
X-1564200Y-119855D01*
Y-95197D01*
X-1556803Y-87800D01*
X-1539197D01*
X-1522800Y-104197D01*
Y-107997D01*
X-1503297Y-127500D01*
X-1494617D01*
X-1492107Y-130010D01*
X-1485637D01*
X-1484750Y-130897D01*
Y-133707D01*
X-1483467Y-134990D01*
X-1478593D01*
X-1476693Y-136890D01*
G01X-1560866Y-123071D02*
X-1558710Y-125227D01*
X-1558135D01*
X-1557500Y-124592D01*
Y-94100D01*
X-1557492Y-94092D01*
Y-94041D01*
X-1554856Y-91406D01*
X-1541194D01*
X-1530200Y-102400D01*
Y-106140D01*
X-1504590Y-131750D01*
X-1499830D01*
X-1492770Y-138810D01*
X-1480140D01*
X-1478550Y-140400D01*
Y-143210D01*
X-1477970Y-143790D01*
X-1473593D01*
X-1471693Y-141890D01*
G01X-1476693Y-151890D02*
X-1478593Y-153790D01*
X-1482970D01*
X-1483550Y-153210D01*
Y-150400D01*
X-1485140Y-148810D01*
X-1488420D01*
X-1490970Y-146260D01*
X-1497900D01*
X-1499070Y-145090D01*
Y-144230D01*
X-1540618Y-102682D01*
Y-99160D01*
X-1543254Y-96524D01*
X-1545076D01*
X-1545100Y-96500D01*
X-1547200D01*
X-1549618Y-98918D01*
Y-119642D01*
X-1550085Y-120109D01*
X-1550836D01*
X-1552992Y-117953D01*
G01X-1560866Y-128583D02*
X-1558710Y-126427D01*
X-1557638D01*
X-1556300Y-125089D01*
Y-94597D01*
X-1556292Y-94589D01*
Y-94538D01*
X-1554359Y-92606D01*
X-1541692D01*
X-1531400Y-102897D01*
Y-106637D01*
X-1505087Y-132950D01*
X-1500327D01*
X-1493267Y-140010D01*
X-1480637D01*
X-1479750Y-140897D01*
Y-143707D01*
X-1478467Y-144990D01*
X-1473593D01*
X-1471693Y-146890D01*
G01X-1476693Y-156890D02*
X-1478593Y-154990D01*
X-1483467D01*
X-1484750Y-153707D01*
Y-150897D01*
X-1485637Y-150010D01*
X-1488917D01*
X-1491467Y-147460D01*
X-1498397D01*
X-1500270Y-145587D01*
Y-144727D01*
X-1541818Y-103179D01*
Y-99657D01*
X-1543751Y-97724D01*
X-1545573D01*
X-1545597Y-97700D01*
X-1546703D01*
X-1548418Y-99415D01*
Y-120139D01*
X-1549588Y-121309D01*
X-1550836D01*
X-1552992Y-123465D01*
G01X-1471693Y-161890D02*
X-1473593Y-163790D01*
X-1477970D01*
X-1478550Y-163210D01*
Y-160400D01*
X-1480140Y-158810D01*
X-1494730D01*
X-1503710Y-149830D01*
Y-146860D01*
X-1514970Y-135600D01*
X-1524300D01*
X-1534673Y-125227D01*
X-1542962D01*
X-1545118Y-123071D01*
G01X-1471693Y-166890D02*
X-1473593Y-164990D01*
X-1478467D01*
X-1479750Y-163707D01*
Y-160897D01*
X-1480637Y-160010D01*
X-1495227D01*
X-1504910Y-150327D01*
Y-147357D01*
X-1515467Y-136800D01*
X-1524797D01*
X-1535170Y-126427D01*
X-1542962D01*
X-1545118Y-128583D01*
G01X-1007500Y-470000D02*
X-1006450Y-475000D01*
X-1005250Y-470000D01*
X-1004050Y-475000D01*
X-1003000Y-470000D01*
G01X-1001125Y-475000D02*
X-999250Y-470000D01*
X-997375Y-475000D01*
G01X-998050Y-473250D02*
X-1000450D01*
G01X-994825Y-474333D02*
X-994225Y-474750D01*
X-993550Y-475000D01*
X-992950D01*
X-992350Y-474750D01*
X-991900Y-474333D01*
X-991675Y-473750D01*
X-991825Y-473167D01*
X-992200Y-472667D01*
X-992875Y-472333D01*
X-993775Y-472167D01*
X-994300Y-471833D01*
X-994525Y-471250D01*
X-994375Y-470667D01*
X-994000Y-470250D01*
X-993475Y-470000D01*
X-992950D01*
X-992425Y-470167D01*
X-991975Y-470583D01*
G01X-988825Y-475000D02*
Y-470000D01*
G01X-985675D02*
Y-475000D01*
G01Y-472500D02*
X-988825D01*
G01X-976525Y-474417D02*
X-976000Y-474833D01*
X-975400Y-475000D01*
X-974800Y-474833D01*
X-974275Y-474333D01*
X-973900Y-473583D01*
X-973750Y-472833D01*
Y-471917D01*
X-973900Y-471167D01*
X-974275Y-470500D01*
X-974725Y-470167D01*
X-975250Y-470000D01*
X-975850Y-470167D01*
X-976300Y-470500D01*
X-976600Y-471000D01*
X-976750Y-471667D01*
X-976600Y-472250D01*
X-976225Y-472833D01*
X-975775Y-473167D01*
X-975250Y-473250D01*
X-974650Y-473083D01*
X-974200Y-472667D01*
X-973750Y-471917D01*
G01X-969250Y-475000D02*
X-968725Y-474917D01*
X-968125Y-474667D01*
X-967750Y-474250D01*
X-967600Y-473667D01*
X-967750Y-473083D01*
X-968200Y-472583D01*
X-968875Y-472333D01*
X-969625D01*
X-970075Y-472167D01*
X-970450Y-471750D01*
X-970600Y-471167D01*
X-970375Y-470583D01*
X-969850Y-470167D01*
X-969250Y-470000D01*
X-968650Y-470167D01*
X-968125Y-470583D01*
X-967900Y-471167D01*
X-968050Y-471750D01*
X-968425Y-472167D01*
X-968875Y-472333D01*
X-969625D01*
X-970300Y-472583D01*
X-970750Y-473083D01*
X-970900Y-473667D01*
X-970750Y-474250D01*
X-970375Y-474667D01*
X-969775Y-474917D01*
X-969250Y-475000D01*
G01X-963250Y-470000D02*
X-963850Y-470167D01*
X-964300Y-470583D01*
X-964600Y-471083D01*
X-964825Y-471750D01*
X-964900Y-472500D01*
X-964825Y-473250D01*
X-964600Y-473917D01*
X-964300Y-474417D01*
X-963850Y-474833D01*
X-963250Y-475000D01*
X-962650Y-474833D01*
X-962200Y-474417D01*
X-961900Y-473917D01*
X-961675Y-473250D01*
X-961600Y-472500D01*
X-961675Y-471750D01*
X-961900Y-471083D01*
X-962200Y-470583D01*
X-962650Y-470167D01*
X-963250Y-470000D01*
G01X-958900Y-474250D02*
X-958450Y-474667D01*
X-957925Y-474917D01*
X-957250Y-475000D01*
X-956575Y-474833D01*
X-956050Y-474500D01*
X-955675Y-473917D01*
X-955600Y-473250D01*
X-955750Y-472583D01*
X-956125Y-472167D01*
X-956650Y-471833D01*
X-957175Y-471750D01*
X-957700Y-471833D01*
X-958375Y-472167D01*
X-958150Y-470000D01*
X-956125D01*
G01X-952675Y-470833D02*
X-952225Y-470333D01*
X-951700Y-470083D01*
X-951100Y-470000D01*
X-950350Y-470167D01*
X-949825Y-470583D01*
X-949675Y-471083D01*
X-949750Y-471583D01*
X-950050Y-472000D01*
X-951550Y-472833D01*
X-952225Y-473417D01*
X-952675Y-474250D01*
X-952825Y-475000D01*
X-949675D01*
G01X-946225Y-473333D02*
X-944275D01*
G01X-940675Y-472917D02*
X-940150Y-472333D01*
X-939700Y-472000D01*
X-939100Y-471833D01*
X-938575Y-472000D01*
X-938200Y-472333D01*
X-937900Y-472833D01*
X-937825Y-473417D01*
X-937900Y-473917D01*
X-938200Y-474417D01*
X-938650Y-474833D01*
X-939175Y-475000D01*
X-939775Y-474833D01*
X-940300Y-474333D01*
X-940600Y-473583D01*
X-940675Y-472750D01*
X-940525Y-471667D01*
X-940300Y-471083D01*
X-939925Y-470500D01*
X-939400Y-470083D01*
X-938875Y-470000D01*
X-938350Y-470167D01*
X-937975Y-470583D01*
G01X-934900Y-474000D02*
X-934450Y-474583D01*
X-933850Y-474917D01*
X-933175Y-475000D01*
X-932575Y-474917D01*
X-931975Y-474500D01*
X-931600Y-474000D01*
X-931525Y-473500D01*
X-931675Y-472917D01*
X-932200Y-472500D01*
X-932725Y-472333D01*
X-933400D01*
G01X-932725D02*
X-932275Y-472083D01*
X-931900Y-471667D01*
X-931750Y-471167D01*
X-931900Y-470667D01*
X-932275Y-470250D01*
X-932950Y-470000D01*
X-933625Y-470083D01*
X-934300Y-470417D01*
G01X-928525Y-474417D02*
X-928000Y-474833D01*
X-927400Y-475000D01*
X-926800Y-474833D01*
X-926275Y-474333D01*
X-925900Y-473583D01*
X-925750Y-472833D01*
Y-471917D01*
X-925900Y-471167D01*
X-926275Y-470500D01*
X-926725Y-470167D01*
X-927250Y-470000D01*
X-927850Y-470167D01*
X-928300Y-470500D01*
X-928600Y-471000D01*
X-928750Y-471667D01*
X-928600Y-472250D01*
X-928225Y-472833D01*
X-927775Y-473167D01*
X-927250Y-473250D01*
X-926650Y-473083D01*
X-926200Y-472667D01*
X-925750Y-471917D01*
G01X-922525Y-474417D02*
X-922000Y-474833D01*
X-921400Y-475000D01*
X-920800Y-474833D01*
X-920275Y-474333D01*
X-919900Y-473583D01*
X-919750Y-472833D01*
Y-471917D01*
X-919900Y-471167D01*
X-920275Y-470500D01*
X-920725Y-470167D01*
X-921250Y-470000D01*
X-921850Y-470167D01*
X-922300Y-470500D01*
X-922600Y-471000D01*
X-922750Y-471667D01*
X-922600Y-472250D01*
X-922225Y-472833D01*
X-921775Y-473167D01*
X-921250Y-473250D01*
X-920650Y-473083D01*
X-920200Y-472667D01*
X-919750Y-471917D01*
G01X-1006750Y-465000D02*
Y-460000D01*
X-1004875D01*
X-1004275Y-460250D01*
X-1003900Y-460583D01*
X-1003750Y-461250D01*
X-1003900Y-461917D01*
X-1004350Y-462333D01*
X-1004875Y-462583D01*
X-1006750D01*
G01X-1004875D02*
X-1003750Y-465000D01*
G01X-997750D02*
X-1000750D01*
Y-460000D01*
X-997750D01*
G01X-998950Y-462417D02*
X-1000750D01*
G01X-994900Y-465000D02*
Y-460000D01*
X-993400D01*
X-992800Y-460250D01*
X-992350Y-460583D01*
X-991975Y-461083D01*
X-991675Y-461667D01*
X-991600Y-462500D01*
X-991675Y-463333D01*
X-991975Y-463917D01*
X-992350Y-464417D01*
X-992800Y-464750D01*
X-993400Y-465000D01*
X-994900D01*
G01X-989200D02*
Y-460000D01*
X-987250Y-464167D01*
X-985300Y-460000D01*
Y-465000D01*
G01X-981250D02*
X-981850Y-464917D01*
X-982375Y-464583D01*
X-982825Y-464083D01*
X-983125Y-463500D01*
X-983275Y-462833D01*
Y-462167D01*
X-983125Y-461500D01*
X-982825Y-460917D01*
X-982375Y-460417D01*
X-981850Y-460083D01*
X-981250Y-460000D01*
X-980650Y-460083D01*
X-980125Y-460417D01*
X-979675Y-460917D01*
X-979375Y-461500D01*
X-979225Y-462167D01*
Y-462833D01*
X-979375Y-463500D01*
X-979675Y-464083D01*
X-980125Y-464583D01*
X-980650Y-464917D01*
X-981250Y-465000D01*
G01X-976975D02*
Y-460000D01*
X-973525Y-465000D01*
Y-460000D01*
G01X-970900Y-465000D02*
Y-460000D01*
X-969400D01*
X-968800Y-460250D01*
X-968350Y-460583D01*
X-967975Y-461083D01*
X-967675Y-461667D01*
X-967600Y-462500D01*
X-967675Y-463333D01*
X-967975Y-463917D01*
X-968350Y-464417D01*
X-968800Y-464750D01*
X-969400Y-465000D01*
X-970900D01*
G01X-1005250Y-455000D02*
Y-450000D01*
X-1006150Y-451000D01*
G01Y-455000D02*
X-1004350D01*
G01X-995200D02*
Y-450000D01*
X-993250Y-454167D01*
X-991300Y-450000D01*
Y-455000D01*
G01X-988150Y-450000D02*
X-986350D01*
G01X-987250D02*
Y-455000D01*
G01X-988150D02*
X-986350D01*
G01X-979600Y-450417D02*
X-980050Y-450167D01*
X-980575Y-450000D01*
X-981175D01*
X-981850Y-450250D01*
X-982375Y-450667D01*
X-982750Y-451167D01*
X-983050Y-452000D01*
X-983125Y-452750D01*
X-982975Y-453500D01*
X-982750Y-454000D01*
X-982300Y-454500D01*
X-981775Y-454833D01*
X-981250Y-455000D01*
X-980725D01*
X-980200Y-454833D01*
X-979750Y-454583D01*
X-979375Y-454250D01*
G01X-976750Y-455000D02*
Y-450000D01*
X-974875D01*
X-974275Y-450250D01*
X-973900Y-450583D01*
X-973750Y-451250D01*
X-973900Y-451917D01*
X-974350Y-452333D01*
X-974875Y-452583D01*
X-976750D01*
G01X-974875D02*
X-973750Y-455000D01*
G01X-969250D02*
X-969850Y-454917D01*
X-970375Y-454583D01*
X-970825Y-454083D01*
X-971125Y-453500D01*
X-971275Y-452833D01*
Y-452167D01*
X-971125Y-451500D01*
X-970825Y-450917D01*
X-970375Y-450417D01*
X-969850Y-450083D01*
X-969250Y-450000D01*
X-968650Y-450083D01*
X-968125Y-450417D01*
X-967675Y-450917D01*
X-967375Y-451500D01*
X-967225Y-452167D01*
Y-452833D01*
X-967375Y-453500D01*
X-967675Y-454083D01*
X-968125Y-454583D01*
X-968650Y-454917D01*
X-969250Y-455000D01*
G01X-964825Y-454333D02*
X-964225Y-454750D01*
X-963550Y-455000D01*
X-962950D01*
X-962350Y-454750D01*
X-961900Y-454333D01*
X-961675Y-453750D01*
X-961825Y-453167D01*
X-962200Y-452667D01*
X-962875Y-452333D01*
X-963775Y-452167D01*
X-964300Y-451833D01*
X-964525Y-451250D01*
X-964375Y-450667D01*
X-964000Y-450250D01*
X-963475Y-450000D01*
X-962950D01*
X-962425Y-450167D01*
X-961975Y-450583D01*
G01X-957250Y-455000D02*
X-957850Y-454917D01*
X-958375Y-454583D01*
X-958825Y-454083D01*
X-959125Y-453500D01*
X-959275Y-452833D01*
Y-452167D01*
X-959125Y-451500D01*
X-958825Y-450917D01*
X-958375Y-450417D01*
X-957850Y-450083D01*
X-957250Y-450000D01*
X-956650Y-450083D01*
X-956125Y-450417D01*
X-955675Y-450917D01*
X-955375Y-451500D01*
X-955225Y-452167D01*
Y-452833D01*
X-955375Y-453500D01*
X-955675Y-454083D01*
X-956125Y-454583D01*
X-956650Y-454917D01*
X-957250Y-455000D01*
G01X-952675D02*
Y-450000D01*
X-949825D01*
G01X-950875Y-452417D02*
X-952675D01*
G01X-945250Y-450000D02*
Y-455000D01*
G01X-946975Y-450000D02*
X-943525D01*
G01X-935500D02*
X-934450Y-455000D01*
X-933250Y-450000D01*
X-932050Y-455000D01*
X-931000Y-450000D01*
G01X-929125Y-455000D02*
X-927250Y-450000D01*
X-925375Y-455000D01*
G01X-926050Y-453250D02*
X-928450D01*
G01X-921250Y-455000D02*
Y-452750D01*
X-922750Y-450000D01*
G01X-919750D02*
X-921250Y-452750D01*
G01X-745906Y-173071D02*
X-748061Y-170915D01*
X-758615D01*
X-762700Y-175000D01*
X-798500D01*
X-805400Y-168100D01*
Y-154000D01*
X-800839Y-149439D01*
X-797065D01*
X-793728Y-146102D01*
G01X-745906Y-167559D02*
X-748061Y-169715D01*
X-759112D01*
X-763197Y-173800D01*
X-779149D01*
X-779849Y-173100D01*
X-781549D01*
X-782249Y-173800D01*
X-783949D01*
X-784649Y-173100D01*
X-786349D01*
X-787049Y-173800D01*
X-788749D01*
X-789449Y-173100D01*
X-791149D01*
X-791849Y-173800D01*
X-793549D01*
X-794249Y-173100D01*
X-795949D01*
X-796649Y-173800D01*
X-798003D01*
X-801072Y-170731D01*
Y-169828D01*
X-802274Y-168626D01*
X-803177D01*
X-804200Y-167603D01*
Y-163297D01*
X-803500Y-162597D01*
Y-160897D01*
X-804200Y-160197D01*
Y-158497D01*
X-803500Y-157797D01*
Y-156097D01*
X-804200Y-155397D01*
Y-154497D01*
X-800342Y-150639D01*
X-797065D01*
X-793728Y-153976D01*
G01X-738032Y-139606D02*
X-735876Y-141762D01*
X-735376D01*
X-734721Y-141108D01*
Y-94200D01*
X-734657Y-94136D01*
Y-94041D01*
X-732022Y-91406D01*
X-731927D01*
X-702821Y-62300D01*
X-651124D01*
X-629644Y-83780D01*
X-615848D01*
X-614761Y-82693D01*
Y-80360D01*
X-613171Y-78770D01*
X-609981D01*
X-608471Y-80280D01*
Y-82703D01*
X-607384Y-83790D01*
X-603514D01*
X-601614Y-81890D01*
G01X-738032Y-145118D02*
X-735876Y-142962D01*
X-734879D01*
X-733521Y-141605D01*
Y-94697D01*
X-733457Y-94633D01*
Y-94538D01*
X-731525Y-92606D01*
X-731430D01*
X-702324Y-63500D01*
X-651621D01*
X-630141Y-84980D01*
X-615351D01*
X-613561Y-83190D01*
Y-80857D01*
X-612674Y-79970D01*
X-610478D01*
X-609671Y-80777D01*
Y-83200D01*
X-607882Y-84990D01*
X-603514D01*
X-601614Y-86890D01*
G01X-606614Y-91890D02*
X-608514Y-93790D01*
X-612891D01*
X-613471Y-93210D01*
Y-90400D01*
X-615061Y-88810D01*
X-623361D01*
X-626741Y-92190D01*
X-630834D01*
X-655924Y-67100D01*
X-700321D01*
X-726821Y-93600D01*
Y-119428D01*
X-727502Y-120109D01*
X-728002D01*
X-730157Y-117953D01*
G01X-606614Y-96890D02*
X-608514Y-94990D01*
X-613388D01*
X-614671Y-93707D01*
Y-90897D01*
X-615558Y-90010D01*
X-622864D01*
X-626244Y-93390D01*
X-631331D01*
X-656421Y-68300D01*
X-699824D01*
X-725621Y-94097D01*
Y-119925D01*
X-727005Y-121309D01*
X-728002D01*
X-730157Y-123465D01*
G01X-601614Y-101890D02*
X-603514Y-103790D01*
X-607891D01*
X-608471Y-103210D01*
Y-100400D01*
X-610061Y-98810D01*
X-632314D01*
X-659224Y-71900D01*
X-697621D01*
X-718921Y-93200D01*
Y-124850D01*
X-719298Y-125227D01*
X-720128D01*
X-722283Y-123071D01*
G01X-714409Y-117953D02*
X-712254Y-120109D01*
X-711754D01*
X-711035Y-119391D01*
Y-99159D01*
X-711021Y-99145D01*
Y-94000D01*
X-693821Y-76800D01*
X-661624D01*
X-632144Y-106280D01*
X-621991D01*
X-619461Y-108810D01*
X-615061D01*
X-613471Y-110400D01*
Y-113210D01*
X-612891Y-113790D01*
X-608514D01*
X-606614Y-111890D01*
G01X-601614Y-106890D02*
X-603514Y-104990D01*
X-608388D01*
X-609671Y-103707D01*
Y-100897D01*
X-610558Y-100010D01*
X-632811D01*
X-659721Y-73100D01*
X-697124D01*
X-717721Y-93697D01*
Y-125347D01*
X-718801Y-126427D01*
X-720128D01*
X-722283Y-128583D01*
G01X-714409Y-123465D02*
X-712254Y-121309D01*
X-711256D01*
X-709835Y-119888D01*
Y-99656D01*
X-709821Y-99642D01*
Y-94497D01*
X-693324Y-78000D01*
X-662121D01*
X-632641Y-107480D01*
X-622488D01*
X-619958Y-110010D01*
X-615558D01*
X-614671Y-110897D01*
Y-113707D01*
X-613388Y-114990D01*
X-608514D01*
X-606614Y-116890D01*
G01X-706535Y-123071D02*
X-704380Y-125227D01*
X-703880D01*
X-703221Y-124569D01*
Y-94594D01*
X-703222Y-94594D01*
Y-93600D01*
X-703221Y-93600D01*
X-702519Y-92897D01*
X-702518D01*
X-691421Y-81800D01*
X-669012D01*
X-669012Y-81799D01*
X-665037D01*
X-665036Y-81800D01*
X-665024D01*
X-628014Y-118810D01*
X-610061D01*
X-608471Y-120400D01*
Y-123210D01*
X-607891Y-123790D01*
X-603514D01*
X-601614Y-121890D01*
G01X-698661Y-117953D02*
X-696506Y-120109D01*
X-696072D01*
X-695321Y-119358D01*
Y-94700D01*
X-687221Y-86600D01*
X-668621D01*
X-628921Y-126300D01*
X-624041D01*
X-621531Y-128810D01*
X-615061D01*
X-613471Y-130400D01*
Y-133210D01*
X-612891Y-133790D01*
X-608514D01*
X-606614Y-131890D01*
G01X-706535Y-128583D02*
X-704380Y-126427D01*
X-703382D01*
X-702021Y-125066D01*
Y-94097D01*
X-690924Y-83000D01*
X-668515D01*
X-668515Y-82999D01*
X-665534D01*
X-665533Y-83000D01*
X-665521D01*
X-628511Y-120010D01*
X-610558D01*
X-609671Y-120897D01*
Y-123707D01*
X-608388Y-124990D01*
X-603514D01*
X-601614Y-126890D01*
G01X-698661Y-123465D02*
X-696506Y-121309D01*
X-695575D01*
X-694121Y-119855D01*
Y-95197D01*
X-686724Y-87800D01*
X-669118D01*
X-629418Y-127500D01*
X-624538D01*
X-622028Y-130010D01*
X-615558D01*
X-614671Y-130897D01*
Y-133707D01*
X-613388Y-134990D01*
X-608514D01*
X-606614Y-136890D01*
G01X-690787Y-123071D02*
X-688631Y-125227D01*
X-688056D01*
X-687421Y-124592D01*
Y-94100D01*
X-687413Y-94092D01*
Y-94041D01*
X-684778Y-91406D01*
X-670604D01*
X-623200Y-138810D01*
X-610061D01*
X-608471Y-140400D01*
Y-143210D01*
X-607891Y-143790D01*
X-603514D01*
X-601614Y-141890D01*
G01X-682913Y-117953D02*
X-680757Y-120109D01*
X-680006D01*
X-679539Y-119642D01*
Y-98918D01*
X-677121Y-96500D01*
X-675021D01*
X-674998Y-96524D01*
X-673175D01*
X-670539Y-99160D01*
Y-101561D01*
X-644380Y-127720D01*
X-643113D01*
X-627133Y-143700D01*
X-623451D01*
X-618341Y-148810D01*
X-615061D01*
X-613471Y-150400D01*
Y-153210D01*
X-612891Y-153790D01*
X-608514D01*
X-606614Y-151890D01*
G01X-690787Y-128583D02*
X-688632Y-126427D01*
X-687559D01*
X-686221Y-125089D01*
Y-94597D01*
X-686213Y-94589D01*
Y-94538D01*
X-684280Y-92606D01*
X-671102D01*
X-623697Y-140010D01*
X-610558D01*
X-609671Y-140897D01*
Y-143707D01*
X-608388Y-144990D01*
X-603514D01*
X-601614Y-146890D01*
G01X-682913Y-123465D02*
X-680757Y-121309D01*
X-679509D01*
X-678339Y-120139D01*
Y-99415D01*
X-676624Y-97700D01*
X-675518D01*
X-675495Y-97724D01*
X-673672D01*
X-671739Y-99657D01*
Y-102058D01*
X-644877Y-128920D01*
X-643610D01*
X-627630Y-144900D01*
X-623948D01*
X-618838Y-150010D01*
X-615558D01*
X-614671Y-150897D01*
Y-153707D01*
X-613388Y-154990D01*
X-608514D01*
X-606614Y-156890D01*
G01X-675039Y-123071D02*
X-672883Y-125227D01*
X-660646D01*
X-651573Y-134300D01*
X-644210D01*
X-630680Y-147830D01*
Y-152781D01*
X-624651Y-158810D01*
X-610061D01*
X-608471Y-160400D01*
Y-163210D01*
X-607891Y-163790D01*
X-603514D01*
X-601614Y-161890D01*
G01X-675039Y-128583D02*
X-672883Y-126427D01*
X-661143D01*
X-652070Y-135500D01*
X-644707D01*
X-631880Y-148327D01*
Y-153278D01*
X-625148Y-160010D01*
X-610558D01*
X-609671Y-160897D01*
Y-163707D01*
X-608388Y-164990D01*
X-603514D01*
X-601614Y-166890D01*
G54D17*
X-1600709Y4685D03*
X-1560709D03*
X-1520709D03*
X-1480709D03*
G54D26*
X-1025000Y-50942D03*
Y1459D03*
X-1015157Y-105312D03*
X-997441D03*
X-981693Y-50942D03*
Y1459D03*
X-971850Y-105312D03*
X-954134D03*
X-938386Y-50942D03*
Y1459D03*
X-145079Y-105312D03*
X-154921Y-50942D03*
Y1459D03*
X-127362Y-105312D03*
X-111614Y-50942D03*
Y1459D03*
X-101772Y-105312D03*
X-84055D03*
X-68307Y-50942D03*
Y1459D03*
G54D36*
G01X-874510Y-499000D02*
Y-493000D01*
X-871290Y-499000D01*
Y-493000D01*
G01X-867200Y-499000D02*
X-867760Y-498900D01*
X-868250Y-498500D01*
X-868670Y-497900D01*
X-868950Y-497200D01*
X-869090Y-496400D01*
Y-495600D01*
X-868950Y-494800D01*
X-868670Y-494100D01*
X-868250Y-493500D01*
X-867760Y-493100D01*
X-867200Y-493000D01*
X-866640Y-493100D01*
X-866150Y-493500D01*
X-865730Y-494100D01*
X-865450Y-494800D01*
X-865310Y-495600D01*
Y-496400D01*
X-865450Y-497200D01*
X-865730Y-497900D01*
X-866150Y-498500D01*
X-866640Y-498900D01*
X-867200Y-499000D01*
G01X-861500Y-493000D02*
Y-499000D01*
G01X-863110Y-493000D02*
X-859890D01*
G01X-856640D02*
X-854960D01*
G01X-855800D02*
Y-499000D01*
G01X-856640D02*
X-854960D01*
G01X-848560Y-493500D02*
X-848980Y-493200D01*
X-849470Y-493000D01*
X-850030D01*
X-850660Y-493300D01*
X-851150Y-493800D01*
X-851500Y-494400D01*
X-851780Y-495400D01*
X-851850Y-496300D01*
X-851710Y-497200D01*
X-851500Y-497800D01*
X-851080Y-498400D01*
X-850590Y-498800D01*
X-850100Y-499000D01*
X-849610D01*
X-849120Y-498800D01*
X-848700Y-498500D01*
X-848350Y-498100D01*
G01X-843000Y-499000D02*
X-845800D01*
Y-493000D01*
X-843000D01*
G01X-844120Y-495900D02*
X-845800D01*
G01X-833000Y-499000D02*
X-833560Y-498900D01*
X-834050Y-498500D01*
X-834470Y-497900D01*
X-834750Y-497200D01*
X-834890Y-496400D01*
Y-495600D01*
X-834750Y-494800D01*
X-834470Y-494100D01*
X-834050Y-493500D01*
X-833560Y-493100D01*
X-833000Y-493000D01*
X-832440Y-493100D01*
X-831950Y-493500D01*
X-831530Y-494100D01*
X-831250Y-494800D01*
X-831110Y-495600D01*
Y-496400D01*
X-831250Y-497200D01*
X-831530Y-497900D01*
X-831950Y-498500D01*
X-832440Y-498900D01*
X-833000Y-499000D01*
G01X-828630D02*
Y-493000D01*
X-825970D01*
G01X-826950Y-495900D02*
X-828630D01*
G01X-817300Y-499000D02*
Y-493000D01*
X-815620D01*
X-815060Y-493300D01*
X-814640Y-494000D01*
X-814500Y-494800D01*
X-814640Y-495600D01*
X-814990Y-496200D01*
X-815620Y-496500D01*
X-817300D01*
G01X-811600Y-499000D02*
Y-493000D01*
X-809850D01*
X-809290Y-493300D01*
X-808940Y-493700D01*
X-808800Y-494500D01*
X-808940Y-495300D01*
X-809360Y-495800D01*
X-809850Y-496100D01*
X-811600D01*
G01X-809850D02*
X-808800Y-499000D01*
G01X-804500D02*
X-805060Y-498900D01*
X-805550Y-498500D01*
X-805970Y-497900D01*
X-806250Y-497200D01*
X-806390Y-496400D01*
Y-495600D01*
X-806250Y-494800D01*
X-805970Y-494100D01*
X-805550Y-493500D01*
X-805060Y-493100D01*
X-804500Y-493000D01*
X-803940Y-493100D01*
X-803450Y-493500D01*
X-803030Y-494100D01*
X-802750Y-494800D01*
X-802610Y-495600D01*
Y-496400D01*
X-802750Y-497200D01*
X-803030Y-497900D01*
X-803450Y-498500D01*
X-803940Y-498900D01*
X-804500Y-499000D01*
G01X-800200D02*
Y-493000D01*
X-798520D01*
X-797960Y-493300D01*
X-797540Y-494000D01*
X-797400Y-494800D01*
X-797540Y-495600D01*
X-797890Y-496200D01*
X-798520Y-496500D01*
X-800200D01*
G01X-794500Y-499000D02*
Y-493000D01*
X-792750D01*
X-792190Y-493300D01*
X-791840Y-493700D01*
X-791700Y-494500D01*
X-791840Y-495300D01*
X-792260Y-495800D01*
X-792750Y-496100D01*
X-794500D01*
G01X-792750D02*
X-791700Y-499000D01*
G01X-788240Y-493000D02*
X-786560D01*
G01X-787400D02*
Y-499000D01*
G01X-788240D02*
X-786560D01*
G01X-780300D02*
X-783100D01*
Y-493000D01*
X-780300D01*
G01X-781420Y-495900D02*
X-783100D01*
G01X-776000Y-493000D02*
Y-499000D01*
G01X-777610Y-493000D02*
X-774390D01*
G01X-772050Y-499000D02*
X-770300Y-493000D01*
X-768550Y-499000D01*
G01X-769180Y-496900D02*
X-771420D01*
G01X-766000Y-499000D02*
Y-493000D01*
X-764250D01*
X-763690Y-493300D01*
X-763340Y-493700D01*
X-763200Y-494500D01*
X-763340Y-495300D01*
X-763760Y-495800D01*
X-764250Y-496100D01*
X-766000D01*
G01X-764250D02*
X-763200Y-499000D01*
G01X-758900D02*
Y-496300D01*
X-760300Y-493000D01*
G01X-757500D02*
X-758900Y-496300D01*
G01X-748900Y-499000D02*
Y-493000D01*
X-747220D01*
X-746660Y-493300D01*
X-746240Y-494000D01*
X-746100Y-494800D01*
X-746240Y-495600D01*
X-746590Y-496200D01*
X-747220Y-496500D01*
X-748900D01*
G01X-743200Y-499000D02*
Y-493000D01*
X-741450D01*
X-740890Y-493300D01*
X-740540Y-493700D01*
X-740400Y-494500D01*
X-740540Y-495300D01*
X-740960Y-495800D01*
X-741450Y-496100D01*
X-743200D01*
G01X-741450D02*
X-740400Y-499000D01*
G01X-736100D02*
X-736660Y-498900D01*
X-737150Y-498500D01*
X-737570Y-497900D01*
X-737850Y-497200D01*
X-737990Y-496400D01*
Y-495600D01*
X-737850Y-494800D01*
X-737570Y-494100D01*
X-737150Y-493500D01*
X-736660Y-493100D01*
X-736100Y-493000D01*
X-735540Y-493100D01*
X-735050Y-493500D01*
X-734630Y-494100D01*
X-734350Y-494800D01*
X-734210Y-495600D01*
Y-496400D01*
X-734350Y-497200D01*
X-734630Y-497900D01*
X-735050Y-498500D01*
X-735540Y-498900D01*
X-736100Y-499000D01*
G01X-731800D02*
Y-493000D01*
X-730120D01*
X-729560Y-493300D01*
X-729140Y-494000D01*
X-729000Y-494800D01*
X-729140Y-495600D01*
X-729490Y-496200D01*
X-730120Y-496500D01*
X-731800D01*
G01X-723300Y-499000D02*
X-726100D01*
Y-493000D01*
X-723300D01*
G01X-724420Y-495900D02*
X-726100D01*
G01X-720400Y-499000D02*
Y-493000D01*
X-718650D01*
X-718090Y-493300D01*
X-717740Y-493700D01*
X-717600Y-494500D01*
X-717740Y-495300D01*
X-718160Y-495800D01*
X-718650Y-496100D01*
X-720400D01*
G01X-718650D02*
X-717600Y-499000D01*
G01X-713300Y-493000D02*
Y-499000D01*
G01X-714910Y-493000D02*
X-711690D01*
G01X-707600Y-499000D02*
Y-496300D01*
X-709000Y-493000D01*
G01X-706200D02*
X-707600Y-496300D01*
G01X-701900Y-499200D02*
X-702040Y-499100D01*
Y-498900D01*
X-701900Y-498800D01*
X-701760Y-498900D01*
Y-499100D01*
X-701900Y-499200D01*
G01Y-496500D02*
X-702040Y-496400D01*
Y-496200D01*
X-701900Y-496100D01*
X-701760Y-496200D01*
Y-496400D01*
X-701900Y-496500D01*
G54D18*
X-1545118Y-178189D03*
X-675039D03*
G54D27*
X-1015157Y-95824D03*
X-1012205Y-93068D03*
X-1009252Y-98580D03*
X-1015157Y-80864D03*
X-1012205Y-78108D03*
X-1009252Y-83620D03*
X-1015157Y-65903D03*
X-1012205Y-63147D03*
X-1009252Y-68659D03*
X-1015157Y-50942D03*
X-1012205Y-48187D03*
X-1009252Y-53698D03*
X-1006299Y-95824D03*
X-1000394Y-98580D03*
X-1003346Y-93068D03*
X-997441Y-95824D03*
X-994488Y-93068D03*
X-1000394Y-83620D03*
X-1006299Y-80864D03*
X-1003346Y-78108D03*
X-997441Y-80864D03*
X-994488Y-78108D03*
X-1006299Y-65903D03*
X-1003346Y-63147D03*
X-1000394Y-68659D03*
X-997441Y-65903D03*
X-994488Y-63147D03*
X-1006299Y-50942D03*
X-1003346Y-48187D03*
X-1000394Y-53698D03*
X-997441Y-50942D03*
X-994488Y-48187D03*
X-991535Y-98580D03*
Y-83620D03*
Y-68659D03*
Y-53698D03*
X-971850Y-95824D03*
X-968898Y-93068D03*
X-965945Y-98580D03*
X-962992Y-95824D03*
X-971850Y-80864D03*
X-965945Y-83620D03*
X-962992Y-80864D03*
X-968898Y-78108D03*
X-971850Y-65903D03*
X-965945Y-68659D03*
X-962992Y-65903D03*
X-968898Y-63147D03*
X-971850Y-50942D03*
X-965945Y-53698D03*
X-962992Y-50942D03*
X-968898Y-48187D03*
X-960039Y-93068D03*
X-957087Y-98580D03*
X-954134Y-95824D03*
X-951181Y-93068D03*
X-948228Y-98580D03*
X-960039Y-78108D03*
X-948228Y-83620D03*
X-957087D03*
X-954134Y-80864D03*
X-951181Y-78108D03*
X-960039Y-63147D03*
X-948228Y-68659D03*
X-957087D03*
X-954134Y-65903D03*
X-951181Y-63147D03*
X-960039Y-48187D03*
X-948228Y-53698D03*
X-957087D03*
X-954134Y-50942D03*
X-951181Y-48187D03*
X-145079Y-95824D03*
Y-80864D03*
Y-65903D03*
Y-50942D03*
X-142126Y-93068D03*
X-139173Y-98580D03*
X-136220Y-95824D03*
X-130315Y-98580D03*
X-133268Y-93068D03*
X-127362Y-95824D03*
X-142126Y-78108D03*
X-139173Y-83620D03*
X-130315D03*
X-136220Y-80864D03*
X-133268Y-78108D03*
X-127362Y-80864D03*
X-142126Y-63147D03*
X-139173Y-68659D03*
X-136220Y-65903D03*
X-133268Y-63147D03*
X-130315Y-68659D03*
X-127362Y-65903D03*
X-142126Y-48187D03*
X-139173Y-53698D03*
X-136220Y-50942D03*
X-133268Y-48187D03*
X-130315Y-53698D03*
X-127362Y-50942D03*
X-121457Y-98580D03*
X-124409Y-93068D03*
X-121457Y-83620D03*
X-124409Y-78108D03*
X-121457Y-68659D03*
X-124409Y-63147D03*
X-121457Y-53698D03*
X-124409Y-48187D03*
X-101772Y-95824D03*
X-98819Y-93068D03*
X-95866Y-98580D03*
X-101772Y-80864D03*
X-95866Y-83620D03*
X-98819Y-78108D03*
X-101772Y-65903D03*
X-95866Y-68659D03*
X-98819Y-63147D03*
X-101772Y-50942D03*
X-95866Y-53698D03*
X-98819Y-48187D03*
X-92913Y-95824D03*
X-89961Y-93068D03*
X-87008Y-98580D03*
X-84055Y-95824D03*
X-81102Y-93068D03*
X-92913Y-80864D03*
X-89961Y-78108D03*
X-87008Y-83620D03*
X-84055Y-80864D03*
X-81102Y-78108D03*
X-92913Y-65903D03*
X-89961Y-63147D03*
X-87008Y-68659D03*
X-84055Y-65903D03*
X-81102Y-63147D03*
X-92913Y-50942D03*
X-89961Y-48187D03*
X-87008Y-53698D03*
X-84055Y-50942D03*
X-81102Y-48187D03*
X-78150Y-98580D03*
Y-83620D03*
Y-68659D03*
Y-53698D03*
G54D37*
G01X-1189134Y-173071D02*
X-1190912Y-174849D01*
G02X-1191209Y-174972I-297J297D01*
G01X-1192100D01*
G03X-1194300Y-177172I0J-2200D01*
G01Y-180500D01*
G02X-1195900Y-182100I-1600J0D01*
G01X-1202849D01*
G02X-1207424Y-180205I0J6470D01*
G01X-1216950Y-170679D01*
G03X-1219989Y-169420I-3039J-3039D01*
G01X-1264088D01*
G03X-1268768Y-174100I0J-4680D01*
G01Y-181838D01*
G02X-1269513Y-183637I-2544J0D01*
G01X-1189134Y-178583D02*
X-1190912Y-176805D01*
G03X-1191209Y-176682I-297J-297D01*
G01X-1192100D01*
G03X-1192590Y-177172I0J-490D01*
G01Y-180500D01*
G02X-1195900Y-183810I-3310J0D01*
G01X-1202849D01*
G02X-1208633Y-181414I0J8180D01*
G01X-1218159Y-171888D01*
G03X-1219989Y-171130I-1830J-1830D01*
G01X-1241802D01*
X-1242342Y-171670D01*
X-1243962D01*
X-1244502Y-171130D01*
X-1246252D01*
X-1247152Y-172030D01*
X-1248772D01*
X-1249672Y-171130D01*
X-1251292D01*
X-1252192Y-172030D01*
X-1253812D01*
X-1254712Y-171130D01*
X-1256332D01*
X-1257232Y-172030D01*
X-1258852D01*
X-1259752Y-171130D01*
X-1264088D01*
G03X-1267058Y-174100I0J-2970D01*
G01Y-181838D01*
G03X-1266313Y-183637I2544J0D01*
G01X-1197008Y-151417D02*
X-1195230Y-153195D01*
G03X-1194933Y-153318I297J297D01*
G01X-1194513D01*
G03X-1193979Y-152784I0J534D01*
G01Y-129235D01*
G03X-1195029Y-126700I-3585J0D01*
G03X-1198779I-1875J-1875D01*
G02X-1204331Y-129000I-5553J5553D01*
G01X-1212654D01*
G03X-1216879Y-130750I0J-5975D01*
G01X-1217532Y-131403D01*
Y-132553D01*
X-1218677Y-133698D01*
X-1219827D01*
X-1220973Y-134844D01*
Y-135994D01*
X-1222118Y-137139D01*
X-1223268D01*
X-1224414Y-138285D01*
Y-139435D01*
X-1225559Y-140580D01*
X-1226709D01*
X-1227855Y-141726D01*
Y-142876D01*
X-1229000Y-144021D01*
X-1230150D01*
X-1240149Y-154020D01*
G02X-1262190Y-163150I-22041J22041D01*
G01X-1264643D01*
G02X-1270343Y-157450I0J5700D01*
G01Y-153579D01*
G03X-1271088Y-151780I-2544J0D01*
G01X-1197008Y-156929D02*
X-1195230Y-155151D01*
G02X-1194933Y-155028I297J-297D01*
G01X-1194513D01*
G03X-1192269Y-152784I0J2244D01*
G01Y-129235D01*
G03X-1193820Y-125491I-5295J0D01*
G03X-1199988I-3084J-3084D01*
G02X-1204331Y-127290I-4344J4344D01*
G01X-1212654D01*
G03X-1218088Y-129541I0J-7685D01*
G01X-1241358Y-152811D01*
G02X-1262190Y-161440I-20832J20832D01*
G01X-1264643D01*
G02X-1268633Y-157450I0J3990D01*
G01Y-153579D01*
G02X-1267888Y-151780I2544J0D01*
G01X-1173386Y-173071D02*
X-1175019Y-174704D01*
G02X-1175710Y-174990I-691J691D01*
G02X-1176400Y-174300I0J690D01*
G01Y-128053D01*
G03X-1178700Y-122500I-7853J0D01*
G03X-1186184Y-119400I-7484J-7484D01*
G01X-1219006D01*
G03X-1242039Y-128941I0J-32574D01*
G02X-1248893Y-131780I-6854J6854D01*
G01X-1256660D01*
G03X-1260850Y-135970I0J-4190D01*
G01Y-142970D01*
G02X-1261338Y-144148I-1666J0D01*
G01X-1261625Y-144435D01*
G01X-1173386Y-178583D02*
X-1174956Y-177012D01*
G03X-1175710Y-176700I-754J-754D01*
G02X-1178110Y-174300I0J2400D01*
G01Y-128053D01*
G03X-1179909Y-123709I-6143J0D01*
G03X-1186184Y-121110I-6275J-6275D01*
G01X-1199500D01*
X-1200590Y-122200D01*
X-1202300D01*
X-1203390Y-121110D01*
X-1207610D01*
X-1208610Y-122110D01*
X-1210000D01*
X-1211000Y-121110D01*
X-1219006D01*
G03X-1240830Y-130150I0J-30864D01*
G02X-1248893Y-133490I-8063J8063D01*
G01X-1252097D01*
X-1252997Y-134390D01*
X-1254617D01*
X-1255517Y-133490D01*
X-1256660D01*
G03X-1259140Y-135970I0J-2480D01*
G01Y-136790D01*
X-1258830Y-137100D01*
Y-139120D01*
X-1259140Y-139430D01*
Y-142970D01*
G03X-1258609Y-144252I1813J0D01*
G01X-1258425Y-144435D01*
G01X-1220590Y-149900D02*
G03X-1221335Y-151699I1799J-1799D01*
G01Y-153960D01*
X-1220820Y-154475D01*
Y-156377D01*
X-1221335Y-156892D01*
Y-159000D01*
G03X-1219705Y-160630I1630J0D01*
G01X-1218015D01*
X-1217115Y-159730D01*
X-1215495D01*
X-1214595Y-160630D01*
X-1212975D01*
X-1212075Y-159730D01*
X-1210455D01*
X-1209555Y-160630D01*
X-1207935D01*
X-1207035Y-159730D01*
X-1205415D01*
X-1204515Y-160630D01*
X-1202663D01*
G02X-1199923Y-163370I0J-2740D01*
G01Y-169434D01*
G03X-1199503Y-169854I420J0D01*
G01X-1199083D01*
G03X-1198786Y-169731I0J420D01*
G01X-1197008Y-167953D01*
G01Y-173465D02*
X-1198786Y-171687D01*
G03X-1199083Y-171564I-297J-297D01*
G01X-1199503D01*
G02X-1201633Y-169434I0J2130D01*
G01Y-163370D01*
G03X-1202663Y-162340I-1030J0D01*
G01X-1219705D01*
G02X-1223045Y-159000I0J3340D01*
G01Y-151699D01*
G03X-1223790Y-149900I-2544J0D01*
G01X-1123450Y-155183D02*
G02X-1122705Y-156982I-1799J-1799D01*
G01Y-158700D01*
G02X-1125405Y-161400I-2700J0D01*
G01X-1132100D01*
G02X-1132500Y-161000I0J400D01*
G03X-1133200Y-160300I-700J0D01*
G01X-1134300D01*
G03X-1135000Y-161000I0J-700D01*
G02X-1135400Y-161400I-400J0D01*
G01X-1141100D01*
G02X-1141500Y-161000I0J400D01*
G03X-1142320Y-160180I-820J0D01*
G01X-1143180D01*
G03X-1144000Y-161000I0J-820D01*
G02X-1144400Y-161400I-400J0D01*
G01X-1149479D01*
G02X-1150162Y-161117I0J966D01*
G01X-1151179Y-160100D01*
X-1151812Y-159467D01*
G03X-1154300Y-158436I-2488J-2488D01*
G01X-1155563D01*
G02X-1155860Y-158313I0J420D01*
G01X-1157638Y-156535D01*
G01X-1120250Y-155183D02*
G03X-1120995Y-156982I1799J-1799D01*
G01Y-158700D01*
G02X-1125405Y-163110I-4410J0D01*
G01X-1149479D01*
G02X-1151371Y-162326I0J2676D01*
G01X-1152388Y-161309D01*
X-1153021Y-160676D01*
G03X-1154300Y-160146I-1279J-1279D01*
G01X-1155563D01*
G03X-1155860Y-160269I0J-420D01*
G01X-1157638Y-162047D01*
G01X-1108703Y-118455D02*
G02X-1110502Y-119200I-1799J1799D01*
G01X-1133900D01*
G03X-1147600Y-132900I0J-13700D01*
G02X-1149651Y-137851I-7001J0D01*
G01X-1153134Y-141334D01*
G02X-1154502Y-141901I-1368J1368D01*
G01X-1155563D01*
G02X-1155860Y-141778I0J420D01*
G01X-1157638Y-140000D01*
G01X-1108703Y-121655D02*
G03X-1110488Y-120916I-1785J-1785D01*
G01X-1112491D01*
G03X-1113000Y-121500I81J-584D01*
G02X-1113520Y-122020I-520J0D01*
G01X-1114980D01*
G02X-1115500Y-121500I0J520D01*
G01Y-121410D01*
G03X-1116000Y-120910I-500J0D01*
G01X-1121000D01*
G03X-1121500Y-121410I0J-500D01*
G01Y-121500D01*
G02X-1122100Y-122100I-600J0D01*
G01X-1123400D01*
G02X-1124000Y-121500I0J600D01*
G01Y-121479D01*
G03X-1124569Y-120910I-569J0D01*
G01X-1133900D01*
G03X-1145890Y-132900I0J-11990D01*
G02X-1148441Y-139060I-8711J0D01*
G01X-1151925Y-142543D01*
G02X-1154502Y-143611I-2577J2577D01*
G01X-1155563D01*
G03X-1155860Y-143734I0J-420D01*
G01X-1157638Y-145512D01*
G01X-1006614Y-162047D02*
Y-161875D01*
G03X-1008279Y-160210I-1665J0D01*
G01X-1008979D01*
G02X-1011389Y-157800I0J2410D01*
G01Y-126620D01*
G03X-1011809Y-126200I-420J0D01*
G01X-1012009D01*
G02X-1012529Y-125680I0J520D01*
G01Y-124250D01*
G02X-1012079Y-123800I450J0D01*
G03X-1011389Y-123110I0J690D01*
G01Y-120000D01*
G03X-1014079Y-117310I-2690J0D01*
G01X-1023179D01*
G02X-1026689Y-113800I0J3510D01*
G01Y-113190D01*
G03X-1027109Y-112770I-420J0D01*
G01X-1027500D01*
G02X-1027979Y-112291I0J479D01*
G01Y-110979D01*
G02X-1027500Y-110500I479J0D01*
G01X-1027109D01*
G03X-1026689Y-110080I0J420D01*
G01Y-103311D01*
G03X-1026830Y-102970I-483J0D01*
G01X-1027400Y-102400D01*
Y-100100D01*
X-1026830Y-99530D01*
G03X-1026689Y-99189I-341J341D01*
G01Y-65790D01*
G02X-1019039Y-58140I7650J0D01*
G01X-1003174D01*
G03X-1002249Y-57935I0J2185D01*
G02X-1000329Y-57350I3015J-6457D01*
G02X-994729Y-57190I5600J-97920D01*
G01X-991304D01*
G03X-988500Y-54386I0J2804D01*
G01Y-47980D01*
G03X-991370Y-45110I-2870J0D01*
G01X-996200D01*
G03X-998790Y-47700I0J-2590D01*
G02X-1000039Y-50716I-4266J0D01*
G01X-1000280Y-50957D01*
G02X-1000781Y-51329I-1506J1506D01*
G01X-1001096Y-51498D01*
G03X-1001268Y-52066I198J-370D01*
G01X-1000394Y-53698D01*
G01X-1006614Y-156535D02*
Y-156835D01*
G02X-1008279Y-158500I-1665J0D01*
G01X-1008979D01*
G02X-1009679Y-157800I0J700D01*
G01Y-120000D01*
G03X-1014079Y-115600I-4400J0D01*
G01X-1023179D01*
G02X-1024979Y-113800I0J1800D01*
G01Y-65790D01*
G02X-1019039Y-59850I5940J0D01*
G01X-1003174D01*
G03X-1001526Y-59484I0J3895D01*
G02X-1000066Y-59040I2292J-4908D01*
G02X-994729Y-58900I5337J-101887D01*
G01X-991304D01*
G03X-986790Y-54386I0J4514D01*
G01Y-47980D01*
G03X-991370Y-43400I-4580J0D01*
G01X-996200D01*
G03X-1000500Y-47700I0J-4300D01*
G02X-1001249Y-49507I-2556J0D01*
G01X-1001489Y-49748D01*
G02X-1001588Y-49821I-297J297D01*
G01X-1001904Y-49990D01*
G02X-1002472Y-49819I-198J370D01*
G01X-1003346Y-48187D01*
G01Y-78108D02*
X-1002472Y-79740D01*
G02X-1002644Y-80308I-370J-198D01*
G01X-1003014Y-80507D01*
G03X-1004234Y-81841I1285J-2399D01*
G02X-1005071Y-83063I-3446J1464D01*
G01X-1005080Y-83072D01*
X-1005630Y-83622D01*
G03X-1006930Y-86760I3138J-3138D01*
G01Y-87020D01*
G02X-1007700Y-87790I-770J0D01*
G01X-1012179D01*
G03X-1015863Y-89316I0J-5211D01*
G01X-1016988Y-90441D01*
G03X-1020579Y-99110I8669J-8669D01*
G01Y-105500D01*
G03X-1018528Y-110451I7001J0D01*
G01X-1018479Y-110500D01*
G03X-1015316Y-111810I3163J3163D01*
G01X-1005969D01*
G02X-1003579Y-114200I0J-2390D01*
G01Y-174200D01*
G02X-1004379Y-175000I-800J0D01*
G01X-1004879D01*
G02X-1006614Y-173265I0J1735D01*
G01Y-173071D01*
G01X-1000394Y-83620D02*
X-1001268Y-81988D01*
G03X-1001837Y-81816I-370J-198D01*
G01X-1002207Y-82014D01*
G03X-1002660Y-82510I478J-891D01*
G02X-1003880Y-84290I-5020J2133D01*
G01X-1004421Y-84831D01*
G03X-1005220Y-86760I1929J-1929D01*
G01Y-87020D01*
G02X-1007700Y-89500I-2480J0D01*
G01X-1012179D01*
G03X-1014654Y-90525I0J-3501D01*
G01X-1015779Y-91650D01*
G03X-1018869Y-99110I7460J-7460D01*
G01Y-105500D01*
G03X-1017319Y-109241I5291J0D01*
G01X-1017270Y-109291D01*
G03X-1015316Y-110100I1953J1953D01*
G01X-1005969D01*
G02X-1001869Y-114200I0J-4100D01*
G01Y-119010D01*
G03X-1001279Y-119600I590J0D01*
G01X-1001179D01*
G02X-1000579Y-120200I0J-600D01*
G01Y-121579D01*
G02X-1001000Y-122000I-421J0D01*
G01X-1001369D01*
G03X-1001869Y-122500I0J-500D01*
G01Y-124131D01*
G03X-1001500Y-124500I369J0D01*
G02X-1000679Y-125321I0J-821D01*
G01Y-126220D01*
G02X-1001459Y-127000I-780J0D01*
G01X-1001500D01*
G03X-1001869Y-127369I0J-369D01*
G01Y-174200D01*
G02X-1004379Y-176710I-2510J0D01*
G01X-1004879D01*
G03X-1006614Y-178445I0J-1735D01*
G01Y-178583D01*
G01X-1003346Y-63147D02*
X-1002472Y-64779D01*
G02X-1002644Y-65348I-370J-198D01*
G01X-1002737Y-65397D01*
G03X-1003237Y-65769I1006J-1878D01*
G01X-1004001Y-66533D01*
G03X-1005479Y-70100I3567J-3567D01*
G03X-1001989Y-73590I3490J0D01*
G01X-990069D01*
G02X-988589Y-75070I0J-1480D01*
G01Y-100934D01*
G02X-991259Y-107380I-9116J0D01*
G01X-994579Y-110700D01*
G03X-995579Y-113114I2414J-2414D01*
G01Y-135900D01*
G02X-996379Y-136700I-800J0D01*
G01X-996756D01*
G03X-997128Y-136719I0J-3694D01*
G02X-998740Y-135262I-147J1457D01*
G01Y-134882D01*
G01X-1000394Y-68659D02*
X-1001268Y-67027D01*
G03X-1001837Y-66855I-370J-198D01*
G01X-1001929Y-66905D01*
G03X-1002028Y-66978I198J-370D01*
G01X-1002792Y-67742D01*
G03X-1003769Y-70100I2358J-2358D01*
G03X-1001989Y-71880I1780J0D01*
G01X-990069D01*
G02X-986879Y-75070I0J-3190D01*
G01Y-100934D01*
G02X-990049Y-108589I-10826J0D01*
G01X-993370Y-111909D01*
G03X-993869Y-113114I1205J-1205D01*
G01Y-117631D01*
G03X-993500Y-118000I369J0D01*
G02X-992579Y-118921I0J-921D01*
G01Y-119800D01*
G02X-993279Y-120500I-700J0D01*
G03X-993869Y-121090I0J-590D01*
G01Y-123700D01*
G03X-993269Y-124300I600J0D01*
G01X-993179D01*
G02X-992479Y-125000I0J-700D01*
G01Y-126200D01*
G02X-993279Y-127000I-800J0D01*
G03X-993869Y-127590I0J-590D01*
G01Y-130085D01*
X-993100Y-130854D01*
Y-132321D01*
X-993869Y-133090D01*
Y-135900D01*
G02X-996379Y-138410I-2510J0D01*
G01X-996756D01*
G03X-996956Y-138420I0J-1984D01*
G03X-998740Y-140394I200J-1974D01*
G01X-990866Y-156535D02*
Y-156613D01*
G03X-989052Y-158499I1887J0D01*
G03X-987800Y-157246I0J1252D01*
G01Y-115151D01*
G02X-985630Y-109911I7410J0D01*
G01X-983459Y-107741D01*
G03X-982989Y-106605I-1136J1136D01*
G01Y-64810D01*
G02X-978938Y-55031I13830J0D01*
G01X-978619Y-54712D01*
G02X-974969Y-53200I3650J-3650D01*
G01X-971979D01*
G03X-969579Y-51700I139J2447D01*
G02X-968565Y-50585I2076J-870D01*
G01X-968195Y-50387D01*
G03X-968023Y-49819I-198J370D01*
G01X-968898Y-48187D01*
G01X-965945Y-53698D02*
X-966819Y-52066D01*
G03X-967388Y-51894I-370J-198D01*
G01X-967758Y-52093D01*
G03X-968001Y-52361I255J-477D01*
G02X-972021Y-54910I-3838J1607D01*
G01X-974969D01*
G03X-977410Y-55921I0J-3452D01*
G01X-977729Y-56240D01*
G03X-981279Y-64810I8570J-8570D01*
G01Y-106605D01*
G02X-982250Y-108950I-3316J0D01*
G01X-984170Y-110870D01*
G03X-986090Y-115505I4635J-4635D01*
G01Y-124480D01*
G03X-985570Y-125000I520J0D01*
G01X-985500D01*
G02X-985000Y-125500I0J-500D01*
G01Y-127000D01*
G02X-985500Y-127500I-500J0D01*
G01X-985670D01*
G03X-986090Y-127920I0J-420D01*
G01Y-157346D01*
G02X-988950Y-160206I-2860J0D01*
G02X-989100Y-160210I-150J2506D01*
G01X-989983D01*
G03X-990866Y-161093I0J-883D01*
G01Y-162047D01*
G01X-982992Y-134882D02*
Y-134987D01*
G03X-981179Y-136800I1813J0D01*
G01X-980679D01*
G03X-979979Y-136100I0J700D01*
G01Y-130573D01*
G02X-979079Y-128400I3073J0D01*
G03X-977779Y-125262I-3138J3138D01*
G01Y-93356D01*
G02X-976679Y-90700I3756J0D01*
G03X-976000Y-89061I-1639J1639D01*
G01Y-62280D01*
G02X-971610Y-57890I4390J0D01*
G01X-964550D01*
G03X-961660Y-55000I0J2890D01*
G01Y-53950D01*
G02X-960662Y-51540I3408J0D01*
G01X-959930Y-50808D01*
G02X-959430Y-50437I1506J-1506D01*
G01X-959337Y-50387D01*
G03X-959165Y-49819I-198J370D01*
G01X-960039Y-48187D01*
G01X-982992Y-140394D02*
Y-140323D01*
G02X-981179Y-138510I1813J0D01*
G01X-980679D01*
G03X-978269Y-136100I0J2410D01*
G01Y-134799D01*
X-977500Y-134030D01*
Y-132410D01*
X-978269Y-131641D01*
Y-130573D01*
G02X-977870Y-129609I1363J0D01*
G03X-976069Y-125262I-4348J4348D01*
G01Y-124190D01*
G02X-975479Y-123600I590J0D01*
G03X-974779Y-122900I0J700D01*
G01Y-121721D01*
G03X-975500Y-121000I-721J0D01*
G01X-975649D01*
G02X-976069Y-120580I0J420D01*
G01Y-117390D01*
G02X-975479Y-116800I590J0D01*
G03X-974779Y-116100I0J700D01*
G01Y-115221D01*
G03X-975500Y-114500I-721J0D01*
G01X-975569D01*
G02X-976069Y-114000I0J500D01*
G01Y-93356D01*
G02X-975470Y-91909I2046J0D01*
G03X-974290Y-89061I-2848J2848D01*
G01Y-62280D01*
G02X-971610Y-59600I2680J0D01*
G01X-964550D01*
G03X-959950Y-55000I0J4600D01*
G01Y-53950D01*
G02X-959453Y-52749I1698J0D01*
G01X-958721Y-52017D01*
G02X-958622Y-51944I297J-297D01*
G01X-958530Y-51894D01*
X-958529Y-51894D01*
G02X-957961Y-52066I198J-370D01*
G01X-957087Y-53698D01*
G01X-960039Y-63147D02*
X-959165Y-64779D01*
G02X-959337Y-65348I-370J-198D01*
G01X-959430Y-65397D01*
G03X-959930Y-65769I1006J-1878D01*
G01X-960748Y-66587D01*
G03X-961979Y-69559I2972J-2972D01*
G01Y-69979D01*
G03X-958457Y-73500I3521J0D01*
G01X-947549D01*
G02X-945179Y-75870I0J-2370D01*
G01Y-77456D01*
G03X-941988Y-85159I10894J0D01*
G01X-940971Y-86176D01*
G02X-937279Y-95090I-8914J-8914D01*
G01Y-116509D01*
G02X-940879Y-125200I-12291J0D01*
G01X-945682Y-130003D01*
G03X-947379Y-134100I4097J-4097D01*
G02X-951197Y-143318I-13037J0D01*
G01X-955379Y-147500D01*
X-965879Y-158000D01*
G02X-967086Y-158500I-1207J1207D01*
G01X-972479D01*
G02X-973631Y-158023I0J1629D01*
G01X-975118Y-156535D01*
G01X-957087Y-68659D02*
X-957961Y-67027D01*
G03X-958529Y-66855I-370J-198D01*
G01X-958530Y-66855D01*
X-958622Y-66905D01*
G03X-958721Y-66978I198J-370D01*
G01X-959539Y-67796D01*
G03X-960269Y-69559I1763J-1763D01*
G01Y-69979D01*
G03X-958457Y-71790I1811J0D01*
G01X-947549D01*
G02X-943469Y-75870I0J-4080D01*
G01Y-77456D01*
G03X-940779Y-83950I9184J0D01*
G01X-939762Y-84967D01*
G02X-935569Y-95090I-10123J-10123D01*
G01Y-116509D01*
G02X-939670Y-126409I-14001J0D01*
G01X-944473Y-131212D01*
G03X-945669Y-134100I2888J-2888D01*
G02X-949988Y-144528I-14747J0D01*
G01X-960420Y-154959D01*
X-961500Y-156040D01*
G03Y-157000I480J-480D01*
G02Y-157821I-411J-411D01*
G01X-962179Y-158500D01*
G02X-963500I-661J661D01*
G03X-963960I-230J-230D01*
G01X-964670Y-159209D01*
G02X-967086Y-160210I-2416J2416D01*
G01X-968254D01*
X-969044Y-161000D01*
X-970364D01*
X-971154Y-160210D01*
X-972479D01*
G03X-973848Y-160777I0J-1936D01*
G01X-975118Y-162047D01*
G01Y-140000D02*
G03X-973218Y-141900I1900J0D01*
G01X-971703D01*
G03X-970979Y-141600I0J1024D01*
G01X-970296Y-140917D01*
X-969813Y-140434D01*
X-952627Y-123249D01*
G03X-945110Y-105100I-18149J18149D01*
G01Y-97100D01*
G03X-946730Y-93188I-5533J0D01*
G01X-948584Y-91335D01*
G03X-954679Y-88810I-6095J-6095D01*
G01X-957713D01*
G02X-962131Y-84071I0J4429D01*
G02X-960215Y-80911I7405J-2329D01*
G01X-960153Y-80849D01*
G02X-959652Y-80477I1506J-1506D01*
G01X-959505Y-80398D01*
X-959337Y-80308D01*
G03X-959165Y-79740I-198J370D01*
G01X-960039Y-78108D01*
G01X-957087Y-83620D02*
X-957961Y-81988D01*
G03X-958529Y-81816I-370J-198D01*
G01X-958530Y-81816D01*
X-958845Y-81985D01*
G03X-958944Y-82058I198J-370D01*
G01X-959006Y-82120D01*
G03X-960432Y-84381I4280J-4280D01*
G03X-957713Y-87100I2719J0D01*
G01X-954679D01*
G02X-947374Y-90126I0J-10330D01*
G01X-945521Y-91979D01*
G02X-943400Y-97100I-5121J-5121D01*
G01Y-105100D01*
G02X-951418Y-124458I-27376J0D01*
G01X-962696Y-135736D01*
X-962696Y-136216D01*
Y-136696D01*
X-963842Y-137842D01*
X-964802D01*
X-965948Y-138987D01*
Y-140148D01*
X-966893Y-141093D01*
X-968054D01*
X-969770Y-142809D01*
G02X-971703Y-143610I-1933J1933D01*
G01X-973216D01*
G03X-975118Y-145512I0J-1902D01*
G01X-319055Y-173071D02*
X-320833Y-174849D01*
G02X-321130Y-174972I-297J297D01*
G01X-322021D01*
G03X-324221Y-177172I0J-2200D01*
G01Y-180500D01*
G02X-325821Y-182100I-1600J0D01*
G01X-332770D01*
G02X-337345Y-180205I0J6470D01*
G01X-346871Y-170679D01*
G03X-349910Y-169420I-3039J-3039D01*
G01X-394010D01*
G03X-398690Y-174100I0J-4680D01*
G01Y-181838D01*
G02X-399435Y-183637I-2544J0D01*
G01X-319055Y-178583D02*
X-320833Y-176805D01*
G03X-321130Y-176682I-297J-297D01*
G01X-322021D01*
G03X-322511Y-177172I0J-490D01*
G01Y-180500D01*
G02X-325821Y-183810I-3310J0D01*
G01X-332770D01*
G02X-338554Y-181414I0J8180D01*
G01X-348080Y-171888D01*
G03X-349910Y-171130I-1830J-1830D01*
G01X-371723D01*
X-372263Y-171670D01*
X-373883D01*
X-374423Y-171130D01*
X-376173D01*
X-377073Y-172030D01*
X-378693D01*
X-379593Y-171130D01*
X-381213D01*
X-382113Y-172030D01*
X-383733D01*
X-384633Y-171130D01*
X-386253D01*
X-387153Y-172030D01*
X-388773D01*
X-389673Y-171130D01*
X-394010D01*
G03X-396980Y-174100I0J-2970D01*
G01Y-181838D01*
G03X-396235Y-183637I2544J0D01*
G01X-326929Y-151417D02*
X-325151Y-153195D01*
G03X-324854Y-153318I297J297D01*
G01X-324434D01*
G03X-323900Y-152784I0J534D01*
G01Y-129235D01*
G03X-324950Y-126700I-3585J0D01*
G03X-328700I-1875J-1875D01*
G02X-334253Y-129000I-5553J5553D01*
G01X-342575D01*
G03X-346800Y-130750I0J-5975D01*
G01X-347453Y-131403D01*
Y-132553D01*
X-348598Y-133698D01*
X-349748D01*
X-350894Y-134844D01*
Y-135994D01*
X-352039Y-137139D01*
X-353189D01*
X-354335Y-138285D01*
Y-139435D01*
X-355480Y-140580D01*
X-356630D01*
X-357776Y-141726D01*
Y-142876D01*
X-358921Y-144021D01*
X-360071D01*
X-370070Y-154020D01*
G02X-392111Y-163150I-22041J22041D01*
G01X-394564D01*
G02X-400264Y-157450I0J5700D01*
G01Y-153579D01*
G03X-401009Y-151780I-2544J0D01*
G01X-326929Y-156929D02*
X-325151Y-155151D01*
G02X-324854Y-155028I297J-297D01*
G01X-324434D01*
G03X-322190Y-152784I0J2244D01*
G01Y-129235D01*
G03X-323741Y-125491I-5295J0D01*
G03X-329909I-3084J-3084D01*
G02X-334253Y-127290I-4344J4344D01*
G01X-342575D01*
G03X-348009Y-129541I0J-7685D01*
G01X-371280Y-152811D01*
G02X-392111Y-161440I-20832J20832D01*
G01X-394564D01*
G02X-398554Y-157450I0J3990D01*
G01Y-153579D01*
G02X-397809Y-151780I2544J0D01*
G01X-303307Y-173071D02*
X-304940Y-174704D01*
G02X-305631Y-174990I-691J691D01*
G02X-306321Y-174300I0J690D01*
G01Y-128053D01*
G03X-308621Y-122500I-7853J0D01*
G03X-316105Y-119400I-7484J-7484D01*
G01X-348927D01*
G03X-371960Y-128941I0J-32574D01*
G02X-378815Y-131780I-6854J6854D01*
G01X-386581D01*
G03X-390771Y-135970I0J-4190D01*
G01Y-142970D01*
G02X-391259Y-144148I-1666J0D01*
G01X-391547Y-144435D01*
G01X-303307Y-178583D02*
X-304878Y-177012D01*
G03X-305631Y-176700I-754J-754D01*
G02X-308031Y-174300I0J2400D01*
G01Y-128053D01*
G03X-309830Y-123709I-6143J0D01*
G03X-316105Y-121110I-6275J-6275D01*
G01X-329421D01*
X-330511Y-122200D01*
X-332221D01*
X-333311Y-121110D01*
X-337531D01*
X-338531Y-122110D01*
X-339921D01*
X-340921Y-121110D01*
X-348927D01*
G03X-370751Y-130150I0J-30864D01*
G02X-378815Y-133490I-8063J8063D01*
G01X-382018D01*
X-382918Y-134390D01*
X-384538D01*
X-385438Y-133490D01*
X-386581D01*
G03X-389061Y-135970I0J-2480D01*
G01Y-136790D01*
X-388751Y-137100D01*
Y-139120D01*
X-389061Y-139430D01*
Y-142970D01*
G03X-388530Y-144252I1813J0D01*
G01X-388347Y-144435D01*
G01X-350511Y-149900D02*
G03X-351256Y-151699I1799J-1799D01*
G01Y-153960D01*
X-350741Y-154475D01*
Y-156377D01*
X-351256Y-156892D01*
Y-159000D01*
G03X-349626Y-160630I1630J0D01*
G01X-347936D01*
X-347036Y-159730D01*
X-345416D01*
X-344516Y-160630D01*
X-342896D01*
X-341996Y-159730D01*
X-340376D01*
X-339476Y-160630D01*
X-337856D01*
X-336956Y-159730D01*
X-335336D01*
X-334436Y-160630D01*
X-332584D01*
G02X-329844Y-163370I0J-2740D01*
G01Y-169434D01*
G03X-329424Y-169854I420J0D01*
G01X-329004D01*
G03X-328707Y-169731I0J420D01*
G01X-326929Y-167953D01*
G01Y-173465D02*
X-328707Y-171687D01*
G03X-329004Y-171564I-297J-297D01*
G01X-329424D01*
G02X-331554Y-169434I0J2130D01*
G01Y-163370D01*
G03X-332584Y-162340I-1030J0D01*
G01X-349626D01*
G02X-352966Y-159000I0J3340D01*
G01Y-151699D01*
G03X-353711Y-149900I-2544J0D01*
G01X-253372Y-155183D02*
G02X-252627Y-156982I-1799J-1799D01*
G01Y-158700D01*
G02X-255327Y-161400I-2700J0D01*
G01X-262021D01*
G02X-262421Y-161000I0J400D01*
G03X-263121Y-160300I-700J0D01*
G01X-264221D01*
G03X-264921Y-161000I0J-700D01*
G02X-265321Y-161400I-400J0D01*
G01X-271021D01*
G02X-271421Y-161000I0J400D01*
G03X-272241Y-160180I-820J0D01*
G01X-273101D01*
G03X-273921Y-161000I0J-820D01*
G02X-274321Y-161400I-400J0D01*
G01X-279400D01*
G02X-280083Y-161117I0J966D01*
G01X-281100Y-160100D01*
X-281733Y-159467D01*
G03X-284221Y-158436I-2488J-2488D01*
G01X-285484D01*
G02X-285781Y-158313I0J420D01*
G01X-287559Y-156535D01*
G01X-250172Y-155183D02*
G03X-250917Y-156982I1799J-1799D01*
G01Y-158700D01*
G02X-255327Y-163110I-4410J0D01*
G01X-279400D01*
G02X-281292Y-162326I0J2676D01*
G01X-282309Y-161309D01*
X-282942Y-160676D01*
G03X-284221Y-160146I-1279J-1279D01*
G01X-285484D01*
G03X-285781Y-160269I0J-420D01*
G01X-287559Y-162047D01*
G01X-238624Y-118455D02*
G02X-240423Y-119200I-1799J1799D01*
G01X-263821D01*
G03X-277521Y-132900I0J-13700D01*
G02X-279572Y-137851I-7001J0D01*
G01X-283056Y-141334D01*
G02X-284423Y-141901I-1368J1368D01*
G01X-285484D01*
G02X-285781Y-141778I0J420D01*
G01X-287559Y-140000D01*
G01X-238624Y-121655D02*
G03X-240410Y-120916I-1785J-1785D01*
G01X-242413D01*
G03X-242921Y-121500I81J-584D01*
G02X-243441Y-122020I-520J0D01*
G01X-244901D01*
G02X-245421Y-121500I0J520D01*
G01Y-121410D01*
G03X-245921Y-120910I-500J0D01*
G01X-250921D01*
G03X-251421Y-121410I0J-500D01*
G01Y-121500D01*
G02X-252021Y-122100I-600J0D01*
G01X-253321D01*
G02X-253921Y-121500I0J600D01*
G01Y-121479D01*
G03X-254490Y-120910I-569J0D01*
G01X-263821D01*
G03X-275811Y-132900I0J-11990D01*
G02X-278363Y-139060I-8711J0D01*
G01X-281846Y-142543D01*
G02X-284423Y-143611I-2577J2577D01*
G01X-285484D01*
G03X-285781Y-143734I0J-420D01*
G01X-287559Y-145512D01*
G01X-136535Y-156535D02*
Y-156835D01*
G02X-138200Y-158500I-1665J0D01*
G01X-138900D01*
G02X-139600Y-157800I0J700D01*
G01Y-120000D01*
G03X-144000Y-115600I-4400J0D01*
G01X-153100D01*
G02X-154900Y-113800I0J1800D01*
G01Y-65790D01*
G02X-148960Y-59850I5940J0D01*
G01X-133095D01*
G03X-131447Y-59484I0J3895D01*
G02X-129987Y-59040I2292J-4908D01*
G02X-124650Y-58900I5337J-101887D01*
G01X-121225D01*
G03X-116711Y-54386I0J4514D01*
G01Y-47980D01*
G03X-121291Y-43400I-4580J0D01*
G01X-126121D01*
G03X-130421Y-47700I0J-4300D01*
G02X-131170Y-49507I-2556J0D01*
G01X-131411Y-49748D01*
G02X-131509Y-49821I-297J297D01*
G01X-131825Y-49990D01*
G02X-132393Y-49819I-198J370D01*
G01X-133268Y-48187D01*
G01X-136535Y-162047D02*
Y-161875D01*
G03X-138200Y-160210I-1665J0D01*
G01X-138900D01*
G02X-141310Y-157800I0J2410D01*
G01Y-126620D01*
G03X-141730Y-126200I-420J0D01*
G01X-141930D01*
G02X-142450Y-125680I0J520D01*
G01Y-124250D01*
G02X-142000Y-123800I450J0D01*
G03X-141310Y-123110I0J690D01*
G01Y-120000D01*
G03X-144000Y-117310I-2690J0D01*
G01X-153100D01*
G02X-156610Y-113800I0J3510D01*
G01Y-113190D01*
G03X-157030Y-112770I-420J0D01*
G01X-157421D01*
G02X-157900Y-112291I0J479D01*
G01Y-110979D01*
G02X-157421Y-110500I479J0D01*
G01X-157030D01*
G03X-156610Y-110080I0J420D01*
G01Y-103311D01*
G03X-156751Y-102970I-483J0D01*
G01X-157321Y-102400D01*
Y-100100D01*
X-156751Y-99530D01*
G03X-156610Y-99189I-341J341D01*
G01Y-65790D01*
G02X-148960Y-58140I7650J0D01*
G01X-133095D01*
G03X-132171Y-57935I0J2185D01*
G02X-130250Y-57350I3015J-6457D01*
G02X-124650Y-57190I5600J-97920D01*
G01X-121225D01*
G03X-118421Y-54386I0J2804D01*
G01Y-47980D01*
G03X-121291Y-45110I-2870J0D01*
G01X-126121D01*
G03X-128711Y-47700I0J-2590D01*
G02X-129961Y-50716I-4266J0D01*
G01X-130202Y-50957D01*
G02X-130702Y-51329I-1506J1506D01*
G01X-131017Y-51498D01*
G03X-131189Y-52066I198J-370D01*
G01X-130315Y-53698D01*
G01X-133268Y-78108D02*
X-132393Y-79740D01*
G02X-132565Y-80308I-370J-198D01*
G01X-132936Y-80507D01*
G03X-134155Y-81841I1285J-2399D01*
G02X-134993Y-83063I-3446J1464D01*
G01X-135002Y-83072D01*
X-135551Y-83622D01*
G03X-136851Y-86760I3138J-3138D01*
G01Y-87020D01*
G02X-137621Y-87790I-770J0D01*
G01X-142100D01*
G03X-145784Y-89316I0J-5211D01*
G01X-146909Y-90441D01*
G03X-150500Y-99110I8669J-8669D01*
G01Y-105500D01*
G03X-148449Y-110451I7001J0D01*
G01X-148400Y-110500D01*
G03X-145237Y-111810I3163J3163D01*
G01X-135890D01*
G02X-133500Y-114200I0J-2390D01*
G01Y-174200D01*
G02X-134300Y-175000I-800J0D01*
G01X-134800D01*
G02X-136535Y-173265I0J1735D01*
G01Y-173071D01*
G01X-130315Y-83620D02*
X-131189Y-81988D01*
G03X-131758Y-81816I-370J-198D01*
G01X-132128Y-82014D01*
G03X-132581Y-82510I478J-891D01*
G02X-133801Y-84290I-5020J2133D01*
G01X-134342Y-84831D01*
G03X-135141Y-86760I1929J-1929D01*
G01Y-87020D01*
G02X-137621Y-89500I-2480J0D01*
G01X-142100D01*
G03X-144575Y-90525I0J-3501D01*
G01X-145700Y-91650D01*
G03X-148790Y-99110I7460J-7460D01*
G01Y-105500D01*
G03X-147240Y-109241I5291J0D01*
G01X-147191Y-109291D01*
G03X-145237Y-110100I1953J1953D01*
G01X-135890D01*
G02X-131790Y-114200I0J-4100D01*
G01Y-119010D01*
G03X-131200Y-119600I590J0D01*
G01X-131100D01*
G02X-130500Y-120200I0J-600D01*
G01Y-121579D01*
G02X-130921Y-122000I-421J0D01*
G01X-131290D01*
G03X-131790Y-122500I0J-500D01*
G01Y-124131D01*
G03X-131421Y-124500I369J0D01*
G02X-130600Y-125321I0J-821D01*
G01Y-126220D01*
G02X-131380Y-127000I-780J0D01*
G01X-131421D01*
G03X-131790Y-127369I0J-369D01*
G01Y-174200D01*
G02X-134300Y-176710I-2510J0D01*
G01X-134800D01*
G03X-136535Y-178445I0J-1735D01*
G01Y-178583D01*
G01X-133268Y-63147D02*
X-132393Y-64779D01*
G02X-132565Y-65348I-370J-198D01*
G01X-132566Y-65348D01*
X-132658Y-65397D01*
G03X-133158Y-65769I1006J-1878D01*
G01X-133922Y-66533D01*
G03X-135400Y-70100I3567J-3567D01*
G03X-131910Y-73590I3490J0D01*
G01X-119990D01*
G02X-118510Y-75070I0J-1480D01*
G01Y-100934D01*
G02X-121180Y-107380I-9116J0D01*
G01X-124500Y-110700D01*
G03X-125500Y-113114I2414J-2414D01*
G01Y-135900D01*
G02X-126300Y-136700I-800J0D01*
G01X-126678D01*
G03X-127050Y-136719I0J-3694D01*
G02X-128661Y-135262I-147J1457D01*
G01Y-134882D01*
G01X-130315Y-68659D02*
X-131189Y-67027D01*
G03X-131758Y-66855I-370J-198D01*
G01X-131850Y-66905D01*
G03X-131949Y-66978I198J-370D01*
G01X-132713Y-67742D01*
G03X-133690Y-70100I2358J-2358D01*
G03X-131910Y-71880I1780J0D01*
G01X-119990D01*
G02X-116800Y-75070I0J-3190D01*
G01Y-100934D01*
G02X-119971Y-108589I-10826J0D01*
G01X-123291Y-111909D01*
G03X-123790Y-113114I1205J-1205D01*
G01Y-117631D01*
G03X-123421Y-118000I369J0D01*
G02X-122500Y-118921I0J-921D01*
G01Y-119800D01*
G02X-123200Y-120500I-700J0D01*
G03X-123790Y-121090I0J-590D01*
G01Y-123700D01*
G03X-123190Y-124300I600J0D01*
G01X-123100D01*
G02X-122400Y-125000I0J-700D01*
G01Y-126200D01*
G02X-123200Y-127000I-800J0D01*
G03X-123790Y-127590I0J-590D01*
G01Y-130085D01*
X-123021Y-130854D01*
Y-132321D01*
X-123790Y-133090D01*
Y-135900D01*
G02X-126300Y-138410I-2510J0D01*
G01X-126678D01*
G03X-126878Y-138420I0J-1984D01*
G03X-128661Y-140394I200J-1974D01*
G01X-120787Y-156535D02*
Y-156613D01*
G03X-118973Y-158499I1887J0D01*
G03X-117721Y-157246I0J1252D01*
G01Y-115151D01*
G02X-115551Y-109911I7410J0D01*
G01X-113380Y-107741D01*
G03X-112910Y-106605I-1136J1136D01*
G01Y-64810D01*
G02X-108859Y-55031I13830J0D01*
G01X-108540Y-54712D01*
G02X-104890Y-53200I3650J-3650D01*
G01X-101900D01*
G03X-99500Y-51700I139J2447D01*
G02X-98487Y-50585I2076J-870D01*
G01X-98116Y-50387D01*
G03X-97945Y-49819I-198J370D01*
G01X-98819Y-48187D01*
G01X-95866Y-53698D02*
X-96740Y-52066D01*
G03X-97309Y-51894I-370J-198D01*
G01X-97679Y-52093D01*
G03X-97923Y-52361I255J-477D01*
G02X-101942Y-54910I-3838J1607D01*
G01X-104890D01*
G03X-107331Y-55921I0J-3452D01*
G01X-107650Y-56240D01*
G03X-111200Y-64810I8570J-8570D01*
G01Y-106605D01*
G02X-112171Y-108950I-3316J0D01*
G01X-114091Y-110870D01*
G03X-116011Y-115505I4635J-4635D01*
G01Y-124480D01*
G03X-115491Y-125000I520J0D01*
G01X-115421D01*
G02X-114921Y-125500I0J-500D01*
G01Y-127000D01*
G02X-115421Y-127500I-500J0D01*
G01X-115591D01*
G03X-116011Y-127920I0J-420D01*
G01Y-157346D01*
G02X-118871Y-160206I-2860J0D01*
G02X-119021Y-160210I-150J2506D01*
G01X-119904D01*
G03X-120787Y-161093I0J-883D01*
G01Y-162047D01*
G01X-112913Y-134882D02*
Y-134987D01*
G03X-111100Y-136800I1813J0D01*
G01X-110600D01*
G03X-109900Y-136100I0J700D01*
G01Y-130573D01*
G02X-109000Y-128400I3073J0D01*
G03X-107700Y-125262I-3138J3138D01*
G01Y-93356D01*
G02X-106600Y-90700I3756J0D01*
G03X-105921Y-89061I-1639J1639D01*
G01Y-62280D01*
G02X-101531Y-57890I4390J0D01*
G01X-94471D01*
G03X-91581Y-55000I0J2890D01*
G01Y-53950D01*
G02X-90583Y-51540I3408J0D01*
G01X-89851Y-50808D01*
G02X-89351Y-50437I1506J-1506D01*
G01X-89258Y-50387D01*
G03X-89086Y-49819I-198J370D01*
G01X-89961Y-48187D01*
G01X-112913Y-140394D02*
Y-140323D01*
G02X-111100Y-138510I1813J0D01*
G01X-110600D01*
G03X-108190Y-136100I0J2410D01*
G01Y-134799D01*
X-107421Y-134030D01*
Y-132410D01*
X-108190Y-131641D01*
Y-130573D01*
G02X-107791Y-129609I1363J0D01*
G03X-105990Y-125262I-4348J4348D01*
G01Y-124190D01*
G02X-105400Y-123600I590J0D01*
G03X-104700Y-122900I0J700D01*
G01Y-121721D01*
G03X-105421Y-121000I-721J0D01*
G01X-105570D01*
G02X-105990Y-120580I0J420D01*
G01Y-117390D01*
G02X-105400Y-116800I590J0D01*
G03X-104700Y-116100I0J700D01*
G01Y-115221D01*
G03X-105421Y-114500I-721J0D01*
G01X-105490D01*
G02X-105990Y-114000I0J500D01*
G01Y-93356D01*
G02X-105391Y-91909I2046J0D01*
G03X-104211Y-89061I-2848J2848D01*
G01Y-62280D01*
G02X-101531Y-59600I2680J0D01*
G01X-94471D01*
G03X-89871Y-55000I0J4600D01*
G01Y-53950D01*
G02X-89374Y-52749I1698J0D01*
G01X-88642Y-52017D01*
G02X-88543Y-51944I297J-297D01*
G01X-88451Y-51894D01*
G02X-87882Y-52066I198J-370D01*
G01X-87008Y-53698D01*
G01X-89961Y-63147D02*
X-89086Y-64779D01*
G02X-89258Y-65348I-370J-198D01*
G01X-89351Y-65397D01*
G03X-89851Y-65769I1006J-1878D01*
G01X-90669Y-66587D01*
G03X-91900Y-69559I2972J-2972D01*
G01Y-69979D01*
G03X-88379Y-73500I3521J0D01*
G01X-77470D01*
G02X-75100Y-75870I0J-2370D01*
G01Y-77456D01*
G03X-71909Y-85159I10894J0D01*
G01X-70892Y-86176D01*
G02X-67200Y-95090I-8914J-8914D01*
G01Y-116509D01*
G02X-70800Y-125200I-12291J0D01*
G01X-75603Y-130003D01*
G03X-77300Y-134100I4097J-4097D01*
G02X-81118Y-143318I-13037J0D01*
G01X-85300Y-147500D01*
X-95800Y-158000D01*
G02X-97007Y-158500I-1207J1207D01*
G01X-102400D01*
G02X-103552Y-158023I0J1629D01*
G01X-105039Y-156535D01*
G01X-87008Y-68659D02*
X-87882Y-67027D01*
G03X-88451Y-66855I-370J-198D01*
G01X-88543Y-66905D01*
G03X-88642Y-66978I198J-370D01*
G01X-89460Y-67796D01*
G03X-90190Y-69559I1763J-1763D01*
G01Y-69979D01*
G03X-88379Y-71790I1811J0D01*
G01X-77470D01*
G02X-73390Y-75870I0J-4080D01*
G01Y-77456D01*
G03X-70700Y-83950I9184J0D01*
G01X-69683Y-84967D01*
G02X-65490Y-95090I-10123J-10123D01*
G01Y-116509D01*
G02X-69591Y-126409I-14001J0D01*
G01X-74394Y-131212D01*
G03X-75590Y-134100I2888J-2888D01*
G02X-79909Y-144528I-14747J0D01*
G01X-90341Y-154959D01*
X-91421Y-156040D01*
G03Y-157000I480J-480D01*
G02Y-157821I-411J-411D01*
G01X-92100Y-158500D01*
G02X-93421I-661J661D01*
G03X-93882I-230J-230D01*
G01X-94591Y-159209D01*
G02X-97007Y-160210I-2416J2416D01*
G01X-98175D01*
X-98965Y-161000D01*
X-100285D01*
X-101075Y-160210D01*
X-102400D01*
G03X-103769Y-160777I0J-1936D01*
G01X-105039Y-162047D01*
G01Y-140000D02*
G03X-103139Y-141900I1900J0D01*
G01X-101624D01*
G03X-100900Y-141600I0J1024D01*
G01X-100217Y-140917D01*
X-99734Y-140434D01*
X-82549Y-123249D01*
G03X-75031Y-105100I-18149J18149D01*
G01Y-97100D01*
G03X-76651Y-93188I-5533J0D01*
G03X-76652Y-93188I-3942J-3882D01*
G01X-78505Y-91335D01*
G03X-84600Y-88810I-6095J-6095D01*
G01X-87634D01*
G02X-92053Y-84071I0J4429D01*
G02X-90136Y-80911I7405J-2329D01*
G01X-90074Y-80849D01*
G02X-89574Y-80477I1506J-1506D01*
G01X-89426Y-80398D01*
X-89258Y-80308D01*
G03X-89086Y-79740I-198J370D01*
G01X-89961Y-78108D01*
G01X-87008Y-83620D02*
X-87882Y-81988D01*
G03X-88451Y-81816I-370J-198D01*
G01X-88766Y-81985D01*
G03X-88865Y-82058I198J-370D01*
G01X-88927Y-82120D01*
G03X-90353Y-84381I4280J-4280D01*
G03X-87634Y-87100I2719J0D01*
G01X-84600D01*
G02X-77296Y-90126I0J-10330D01*
G01X-75443Y-91979D01*
G02X-73321Y-97100I-5121J-5121D01*
G01Y-105100D01*
G02X-81340Y-124458I-27376J0D01*
G01X-92618Y-135736D01*
X-92618Y-136216D01*
Y-136696D01*
X-93763Y-137842D01*
X-94724D01*
X-95869Y-138987D01*
Y-140148D01*
X-96815Y-141093D01*
X-97975D01*
X-99691Y-142809D01*
G02X-101624Y-143610I-1933J1933D01*
G01X-103138D01*
G03X-105039Y-145512I0J-1902D01*
G54D28*
X-1003346Y-36375D03*
X-960039D03*
X-133268D03*
X-89961D03*
G54D19*
X-1488693Y-178940D03*
X-1476693Y-64840D03*
X-618614Y-178940D03*
X-606614Y-64840D03*
G54D38*
G01X-1189333Y-572500D02*
Y-565500D01*
X-1187667D01*
X-1187000Y-565850D01*
X-1186500Y-566317D01*
X-1186083Y-567017D01*
X-1185750Y-567833D01*
X-1185667Y-569000D01*
X-1185750Y-570167D01*
X-1186083Y-570983D01*
X-1186500Y-571684D01*
X-1187000Y-572150D01*
X-1187667Y-572500D01*
X-1189333D01*
G01X-1180700D02*
X-1181367Y-572383D01*
X-1181950Y-571917D01*
X-1182450Y-571217D01*
X-1182783Y-570400D01*
X-1182950Y-569467D01*
Y-568533D01*
X-1182783Y-567600D01*
X-1182450Y-566783D01*
X-1181950Y-566083D01*
X-1181367Y-565617D01*
X-1180700Y-565500D01*
X-1180033Y-565617D01*
X-1179450Y-566083D01*
X-1178950Y-566783D01*
X-1178617Y-567600D01*
X-1178450Y-568533D01*
Y-569467D01*
X-1178617Y-570400D01*
X-1178950Y-571217D01*
X-1179450Y-571917D01*
X-1180033Y-572383D01*
X-1180700Y-572500D01*
G01X-1172067Y-566083D02*
X-1172567Y-565733D01*
X-1173150Y-565500D01*
X-1173817D01*
X-1174567Y-565850D01*
X-1175150Y-566433D01*
X-1175567Y-567133D01*
X-1175900Y-568300D01*
X-1175983Y-569350D01*
X-1175817Y-570400D01*
X-1175567Y-571100D01*
X-1175067Y-571800D01*
X-1174483Y-572267D01*
X-1173900Y-572500D01*
X-1173317D01*
X-1172733Y-572267D01*
X-1172233Y-571917D01*
X-1171817Y-571450D01*
G01X-1168933Y-565500D02*
Y-570517D01*
X-1168600Y-571567D01*
X-1167933Y-572267D01*
X-1167100Y-572500D01*
X-1166267Y-572267D01*
X-1165600Y-571567D01*
X-1165267Y-570517D01*
Y-565500D01*
G01X-1162467Y-572500D02*
Y-565500D01*
X-1160300Y-571333D01*
X-1158133Y-565500D01*
Y-572500D01*
G01X-1151833D02*
X-1155167D01*
Y-565500D01*
X-1151833D01*
G01X-1153167Y-568883D02*
X-1155167D01*
G01X-1148617Y-572500D02*
Y-565500D01*
X-1144783Y-572500D01*
Y-565500D01*
G01X-1139900D02*
Y-572500D01*
G01X-1141817Y-565500D02*
X-1137983D01*
G01X-1128217Y-572500D02*
Y-565500D01*
X-1124383Y-572500D01*
Y-565500D01*
G01X-1121333D02*
Y-570517D01*
X-1121000Y-571567D01*
X-1120333Y-572267D01*
X-1119500Y-572500D01*
X-1118667Y-572267D01*
X-1118000Y-571567D01*
X-1117667Y-570517D01*
Y-565500D01*
G01X-1114867Y-572500D02*
Y-565500D01*
X-1112700Y-571333D01*
X-1110533Y-565500D01*
Y-572500D01*
G01X-1105233Y-568767D02*
X-1104900Y-568417D01*
X-1104650Y-567833D01*
X-1104483Y-567017D01*
X-1104650Y-566317D01*
X-1104983Y-565850D01*
X-1105567Y-565500D01*
X-1107817D01*
Y-572500D01*
X-1105067D01*
X-1104483Y-572033D01*
X-1104150Y-571333D01*
X-1103983Y-570517D01*
X-1104150Y-569700D01*
X-1104650Y-569000D01*
X-1105233Y-568767D01*
X-1107817D01*
G01X-1097433Y-572500D02*
X-1100767D01*
Y-565500D01*
X-1097433D01*
G01X-1098767Y-568883D02*
X-1100767D01*
G01X-1093967Y-572500D02*
Y-565500D01*
X-1091883D01*
X-1091217Y-565850D01*
X-1090800Y-566317D01*
X-1090633Y-567250D01*
X-1090800Y-568183D01*
X-1091300Y-568767D01*
X-1091883Y-569117D01*
X-1093967D01*
G01X-1091883D02*
X-1090633Y-572500D01*
G01X-1189250Y-531567D02*
X-1188583Y-532150D01*
X-1187833Y-532500D01*
X-1187167D01*
X-1186500Y-532150D01*
X-1186000Y-531567D01*
X-1185750Y-530750D01*
X-1185917Y-529933D01*
X-1186333Y-529233D01*
X-1187083Y-528767D01*
X-1188083Y-528533D01*
X-1188667Y-528067D01*
X-1188917Y-527250D01*
X-1188750Y-526433D01*
X-1188333Y-525850D01*
X-1187750Y-525500D01*
X-1187167D01*
X-1186583Y-525733D01*
X-1186083Y-526317D01*
G01X-1182450Y-532500D02*
Y-525500D01*
G01X-1178950D02*
Y-532500D01*
G01Y-529000D02*
X-1182450D01*
G01X-1172233Y-532500D02*
X-1175567D01*
Y-525500D01*
X-1172233D01*
G01X-1173567Y-528883D02*
X-1175567D01*
G01X-1165433Y-532500D02*
X-1168767D01*
Y-525500D01*
X-1165433D01*
G01X-1166767Y-528883D02*
X-1168767D01*
G01X-1160300Y-525500D02*
Y-532500D01*
G01X-1162217Y-525500D02*
X-1158383D01*
G01X-1146700D02*
Y-532500D01*
G01X-1148617Y-525500D02*
X-1144783D01*
G01X-1140900D02*
X-1138900D01*
G01X-1139900D02*
Y-532500D01*
G01X-1140900D02*
X-1138900D01*
G01X-1133100Y-525500D02*
Y-532500D01*
G01X-1135017Y-525500D02*
X-1131183D01*
G01X-1127967D02*
Y-532500D01*
X-1124633D01*
G01X-1117833D02*
X-1121167D01*
Y-525500D01*
X-1117833D01*
G01X-1119167Y-528883D02*
X-1121167D01*
G01X-1112700Y-532733D02*
X-1112867Y-532617D01*
Y-532383D01*
X-1112700Y-532267D01*
X-1112533Y-532383D01*
Y-532617D01*
X-1112700Y-532733D01*
G01Y-529584D02*
X-1112867Y-529467D01*
Y-529233D01*
X-1112700Y-529117D01*
X-1112533Y-529233D01*
Y-529467D01*
X-1112700Y-529584D01*
G01X-1187500Y-485500D02*
Y-492500D01*
G01X-1189417Y-485500D02*
X-1185583D01*
G01X-1181700D02*
X-1179700D01*
G01X-1180700D02*
Y-492500D01*
G01X-1181700D02*
X-1179700D01*
G01X-1173900Y-485500D02*
Y-492500D01*
G01X-1175817Y-485500D02*
X-1171983D01*
G01X-1168767D02*
Y-492500D01*
X-1165433D01*
G01X-1158633D02*
X-1161967D01*
Y-485500D01*
X-1158633D01*
G01X-1159967Y-488883D02*
X-1161967D01*
G01X-916667Y-570000D02*
Y-563000D01*
X-914583D01*
X-913917Y-563350D01*
X-913500Y-563817D01*
X-913333Y-564750D01*
X-913500Y-565683D01*
X-914000Y-566267D01*
X-914583Y-566617D01*
X-916667D01*
G01X-914583D02*
X-913333Y-570000D01*
G01X-906533D02*
X-909867D01*
Y-563000D01*
X-906533D01*
G01X-907867Y-566383D02*
X-909867D01*
G01X-903483Y-563000D02*
X-901400Y-570000D01*
X-899317Y-563000D01*
G01X-907850Y-451567D02*
X-907183Y-452150D01*
X-906433Y-452500D01*
X-905767D01*
X-905100Y-452150D01*
X-904600Y-451567D01*
X-904350Y-450750D01*
X-904517Y-449933D01*
X-904933Y-449233D01*
X-905683Y-448767D01*
X-906683Y-448533D01*
X-907267Y-448067D01*
X-907517Y-447250D01*
X-907350Y-446433D01*
X-906933Y-445850D01*
X-906350Y-445500D01*
X-905767D01*
X-905183Y-445733D01*
X-904683Y-446317D01*
G01X-897467Y-446083D02*
X-897967Y-445733D01*
X-898550Y-445500D01*
X-899217D01*
X-899967Y-445850D01*
X-900550Y-446433D01*
X-900967Y-447133D01*
X-901300Y-448300D01*
X-901383Y-449350D01*
X-901217Y-450400D01*
X-900967Y-451100D01*
X-900467Y-451800D01*
X-899883Y-452267D01*
X-899300Y-452500D01*
X-898717D01*
X-898133Y-452267D01*
X-897633Y-451917D01*
X-897217Y-451450D01*
G01X-894583Y-452500D02*
X-892500Y-445500D01*
X-890417Y-452500D01*
G01X-891167Y-450050D02*
X-893833D01*
G01X-887367Y-445500D02*
Y-452500D01*
X-884033D01*
G01X-877233D02*
X-880567D01*
Y-445500D01*
X-877233D01*
G01X-878567Y-448883D02*
X-880567D01*
G01X-874333Y-572500D02*
Y-565500D01*
X-872667D01*
X-872000Y-565850D01*
X-871500Y-566317D01*
X-871083Y-567017D01*
X-870750Y-567833D01*
X-870667Y-569000D01*
X-870750Y-570167D01*
X-871083Y-570983D01*
X-871500Y-571684D01*
X-872000Y-572150D01*
X-872667Y-572500D01*
X-874333D01*
G01X-866700Y-565500D02*
X-864700D01*
G01X-865700D02*
Y-572500D01*
G01X-866700D02*
X-864700D01*
G01X-860650Y-571567D02*
X-859983Y-572150D01*
X-859233Y-572500D01*
X-858567D01*
X-857900Y-572150D01*
X-857400Y-571567D01*
X-857150Y-570750D01*
X-857317Y-569933D01*
X-857733Y-569233D01*
X-858483Y-568767D01*
X-859483Y-568533D01*
X-860067Y-568067D01*
X-860317Y-567250D01*
X-860150Y-566433D01*
X-859733Y-565850D01*
X-859150Y-565500D01*
X-858567D01*
X-857983Y-565733D01*
X-857483Y-566317D01*
G01X-850267Y-566083D02*
X-850767Y-565733D01*
X-851350Y-565500D01*
X-852017D01*
X-852767Y-565850D01*
X-853350Y-566433D01*
X-853767Y-567133D01*
X-854100Y-568300D01*
X-854183Y-569350D01*
X-854017Y-570400D01*
X-853767Y-571100D01*
X-853267Y-571800D01*
X-852683Y-572267D01*
X-852100Y-572500D01*
X-851517D01*
X-850933Y-572267D01*
X-850433Y-571917D01*
X-850017Y-571450D01*
G01X-846967Y-565500D02*
Y-572500D01*
X-843633D01*
G01X-838500D02*
X-839167Y-572383D01*
X-839750Y-571917D01*
X-840250Y-571217D01*
X-840583Y-570400D01*
X-840750Y-569467D01*
Y-568533D01*
X-840583Y-567600D01*
X-840250Y-566783D01*
X-839750Y-566083D01*
X-839167Y-565617D01*
X-838500Y-565500D01*
X-837833Y-565617D01*
X-837250Y-566083D01*
X-836750Y-566783D01*
X-836417Y-567600D01*
X-836250Y-568533D01*
Y-569467D01*
X-836417Y-570400D01*
X-836750Y-571217D01*
X-837250Y-571917D01*
X-837833Y-572383D01*
X-838500Y-572500D01*
G01X-833450Y-571567D02*
X-832783Y-572150D01*
X-832033Y-572500D01*
X-831367D01*
X-830700Y-572150D01*
X-830200Y-571567D01*
X-829950Y-570750D01*
X-830117Y-569933D01*
X-830533Y-569233D01*
X-831283Y-568767D01*
X-832283Y-568533D01*
X-832867Y-568067D01*
X-833117Y-567250D01*
X-832950Y-566433D01*
X-832533Y-565850D01*
X-831950Y-565500D01*
X-831367D01*
X-830783Y-565733D01*
X-830283Y-566317D01*
G01X-823233Y-572500D02*
X-826567D01*
Y-565500D01*
X-823233D01*
G01X-824567Y-568883D02*
X-826567D01*
G01X-819933Y-572500D02*
Y-565500D01*
X-818267D01*
X-817600Y-565850D01*
X-817100Y-566317D01*
X-816683Y-567017D01*
X-816350Y-567833D01*
X-816267Y-569000D01*
X-816350Y-570167D01*
X-816683Y-570983D01*
X-817100Y-571684D01*
X-817600Y-572150D01*
X-818267Y-572500D01*
X-819933D01*
G01X-807000Y-565500D02*
X-805833Y-572500D01*
X-804500Y-565500D01*
X-803167Y-572500D01*
X-802000Y-565500D01*
G01X-798700D02*
X-796700D01*
G01X-797700D02*
Y-572500D01*
G01X-798700D02*
X-796700D01*
G01X-790900Y-565500D02*
Y-572500D01*
G01X-792817Y-565500D02*
X-788983D01*
G01X-785850Y-572500D02*
Y-565500D01*
G01X-782350D02*
Y-572500D01*
G01Y-569000D02*
X-785850D01*
G01X-777300Y-572500D02*
X-777967Y-572383D01*
X-778550Y-571917D01*
X-779050Y-571217D01*
X-779383Y-570400D01*
X-779550Y-569467D01*
Y-568533D01*
X-779383Y-567600D01*
X-779050Y-566783D01*
X-778550Y-566083D01*
X-777967Y-565617D01*
X-777300Y-565500D01*
X-776633Y-565617D01*
X-776050Y-566083D01*
X-775550Y-566783D01*
X-775217Y-567600D01*
X-775050Y-568533D01*
Y-569467D01*
X-775217Y-570400D01*
X-775550Y-571217D01*
X-776050Y-571917D01*
X-776633Y-572383D01*
X-777300Y-572500D01*
G01X-772333Y-565500D02*
Y-570517D01*
X-772000Y-571567D01*
X-771333Y-572267D01*
X-770500Y-572500D01*
X-769667Y-572267D01*
X-769000Y-571567D01*
X-768667Y-570517D01*
Y-565500D01*
G01X-763700D02*
Y-572500D01*
G01X-765617Y-565500D02*
X-761783D01*
G01X-750100D02*
Y-572500D01*
G01X-752017Y-565500D02*
X-748183D01*
G01X-745050Y-572500D02*
Y-565500D01*
G01X-741550D02*
Y-572500D01*
G01Y-569000D02*
X-745050D01*
G01X-734833Y-572500D02*
X-738167D01*
Y-565500D01*
X-734833D01*
G01X-736167Y-568883D02*
X-738167D01*
G01X-724567Y-572500D02*
Y-565500D01*
X-722567D01*
X-721900Y-565850D01*
X-721400Y-566667D01*
X-721233Y-567600D01*
X-721400Y-568533D01*
X-721817Y-569233D01*
X-722567Y-569584D01*
X-724567D01*
G01X-717767Y-572500D02*
Y-565500D01*
X-715683D01*
X-715017Y-565850D01*
X-714600Y-566317D01*
X-714433Y-567250D01*
X-714600Y-568183D01*
X-715100Y-568767D01*
X-715683Y-569117D01*
X-717767D01*
G01X-715683D02*
X-714433Y-572500D01*
G01X-710300Y-565500D02*
X-708300D01*
G01X-709300D02*
Y-572500D01*
G01X-710300D02*
X-708300D01*
G01X-702500D02*
X-703167Y-572383D01*
X-703750Y-571917D01*
X-704250Y-571217D01*
X-704583Y-570400D01*
X-704750Y-569467D01*
Y-568533D01*
X-704583Y-567600D01*
X-704250Y-566783D01*
X-703750Y-566083D01*
X-703167Y-565617D01*
X-702500Y-565500D01*
X-701833Y-565617D01*
X-701250Y-566083D01*
X-700750Y-566783D01*
X-700417Y-567600D01*
X-700250Y-568533D01*
Y-569467D01*
X-700417Y-570400D01*
X-700750Y-571217D01*
X-701250Y-571917D01*
X-701833Y-572383D01*
X-702500Y-572500D01*
G01X-697367D02*
Y-565500D01*
X-695283D01*
X-694617Y-565850D01*
X-694200Y-566317D01*
X-694033Y-567250D01*
X-694200Y-568183D01*
X-694700Y-568767D01*
X-695283Y-569117D01*
X-697367D01*
G01X-695283D02*
X-694033Y-572500D01*
G01X-684600Y-565500D02*
X-683433Y-572500D01*
X-682100Y-565500D01*
X-680767Y-572500D01*
X-679600Y-565500D01*
G01X-676967Y-572500D02*
Y-565500D01*
X-674883D01*
X-674217Y-565850D01*
X-673800Y-566317D01*
X-673633Y-567250D01*
X-673800Y-568183D01*
X-674300Y-568767D01*
X-674883Y-569117D01*
X-676967D01*
G01X-674883D02*
X-673633Y-572500D01*
G01X-669500Y-565500D02*
X-667500D01*
G01X-668500D02*
Y-572500D01*
G01X-669500D02*
X-667500D01*
G01X-661700Y-565500D02*
Y-572500D01*
G01X-663617Y-565500D02*
X-659783D01*
G01X-654900D02*
Y-572500D01*
G01X-656817Y-565500D02*
X-652983D01*
G01X-646433Y-572500D02*
X-649767D01*
Y-565500D01*
X-646433D01*
G01X-647767Y-568883D02*
X-649767D01*
G01X-643217Y-572500D02*
Y-565500D01*
X-639383Y-572500D01*
Y-565500D01*
G01X-625867Y-566083D02*
X-626367Y-565733D01*
X-626950Y-565500D01*
X-627617D01*
X-628367Y-565850D01*
X-628950Y-566433D01*
X-629367Y-567133D01*
X-629700Y-568300D01*
X-629783Y-569350D01*
X-629617Y-570400D01*
X-629367Y-571100D01*
X-628867Y-571800D01*
X-628283Y-572267D01*
X-627700Y-572500D01*
X-627117D01*
X-626533Y-572267D01*
X-626033Y-571917D01*
X-625617Y-571450D01*
G01X-620900Y-572500D02*
X-621567Y-572383D01*
X-622150Y-571917D01*
X-622650Y-571217D01*
X-622983Y-570400D01*
X-623150Y-569467D01*
Y-568533D01*
X-622983Y-567600D01*
X-622650Y-566783D01*
X-622150Y-566083D01*
X-621567Y-565617D01*
X-620900Y-565500D01*
X-620233Y-565617D01*
X-619650Y-566083D01*
X-619150Y-566783D01*
X-618817Y-567600D01*
X-618650Y-568533D01*
Y-569467D01*
X-618817Y-570400D01*
X-619150Y-571217D01*
X-619650Y-571917D01*
X-620233Y-572383D01*
X-620900Y-572500D01*
G01X-616017D02*
Y-565500D01*
X-612183Y-572500D01*
Y-565500D01*
G01X-609050Y-571567D02*
X-608383Y-572150D01*
X-607633Y-572500D01*
X-606967D01*
X-606300Y-572150D01*
X-605800Y-571567D01*
X-605550Y-570750D01*
X-605717Y-569933D01*
X-606133Y-569233D01*
X-606883Y-568767D01*
X-607883Y-568533D01*
X-608467Y-568067D01*
X-608717Y-567250D01*
X-608550Y-566433D01*
X-608133Y-565850D01*
X-607550Y-565500D01*
X-606967D01*
X-606383Y-565733D01*
X-605883Y-566317D01*
G01X-598833Y-572500D02*
X-602167D01*
Y-565500D01*
X-598833D01*
G01X-600167Y-568883D02*
X-602167D01*
G01X-595617Y-572500D02*
Y-565500D01*
X-591783Y-572500D01*
Y-565500D01*
G01X-586900D02*
Y-572500D01*
G01X-588817Y-565500D02*
X-584983D01*
G01X-872500Y-587500D02*
X-873167Y-587383D01*
X-873750Y-586917D01*
X-874250Y-586217D01*
X-874583Y-585400D01*
X-874750Y-584467D01*
Y-583533D01*
X-874583Y-582600D01*
X-874250Y-581783D01*
X-873750Y-581083D01*
X-873167Y-580617D01*
X-872500Y-580500D01*
X-871833Y-580617D01*
X-871250Y-581083D01*
X-870750Y-581783D01*
X-870417Y-582600D01*
X-870250Y-583533D01*
Y-584467D01*
X-870417Y-585400D01*
X-870750Y-586217D01*
X-871250Y-586917D01*
X-871833Y-587383D01*
X-872500Y-587500D01*
G01X-867283D02*
Y-580500D01*
X-864117D01*
G01X-865283Y-583883D02*
X-867283D01*
G01X-854267Y-587500D02*
Y-580500D01*
X-852100Y-586333D01*
X-849933Y-580500D01*
Y-587500D01*
G01X-846300Y-580500D02*
X-844300D01*
G01X-845300D02*
Y-587500D01*
G01X-846300D02*
X-844300D01*
G01X-836667Y-581083D02*
X-837167Y-580733D01*
X-837750Y-580500D01*
X-838417D01*
X-839167Y-580850D01*
X-839750Y-581433D01*
X-840167Y-582133D01*
X-840500Y-583300D01*
X-840583Y-584350D01*
X-840417Y-585400D01*
X-840167Y-586100D01*
X-839667Y-586800D01*
X-839083Y-587267D01*
X-838500Y-587500D01*
X-837917D01*
X-837333Y-587267D01*
X-836833Y-586917D01*
X-836417Y-586450D01*
G01X-833367Y-587500D02*
Y-580500D01*
X-831283D01*
X-830617Y-580850D01*
X-830200Y-581317D01*
X-830033Y-582250D01*
X-830200Y-583183D01*
X-830700Y-583767D01*
X-831283Y-584117D01*
X-833367D01*
G01X-831283D02*
X-830033Y-587500D01*
G01X-824900D02*
X-825567Y-587383D01*
X-826150Y-586917D01*
X-826650Y-586217D01*
X-826983Y-585400D01*
X-827150Y-584467D01*
Y-583533D01*
X-826983Y-582600D01*
X-826650Y-581783D01*
X-826150Y-581083D01*
X-825567Y-580617D01*
X-824900Y-580500D01*
X-824233Y-580617D01*
X-823650Y-581083D01*
X-823150Y-581783D01*
X-822817Y-582600D01*
X-822650Y-583533D01*
Y-584467D01*
X-822817Y-585400D01*
X-823150Y-586217D01*
X-823650Y-586917D01*
X-824233Y-587383D01*
X-824900Y-587500D01*
G01X-819850Y-586567D02*
X-819183Y-587150D01*
X-818433Y-587500D01*
X-817767D01*
X-817100Y-587150D01*
X-816600Y-586567D01*
X-816350Y-585750D01*
X-816517Y-584933D01*
X-816933Y-584233D01*
X-817683Y-583767D01*
X-818683Y-583533D01*
X-819267Y-583067D01*
X-819517Y-582250D01*
X-819350Y-581433D01*
X-818933Y-580850D01*
X-818350Y-580500D01*
X-817767D01*
X-817183Y-580733D01*
X-816683Y-581317D01*
G01X-811300Y-587500D02*
X-811967Y-587383D01*
X-812550Y-586917D01*
X-813050Y-586217D01*
X-813383Y-585400D01*
X-813550Y-584467D01*
Y-583533D01*
X-813383Y-582600D01*
X-813050Y-581783D01*
X-812550Y-581083D01*
X-811967Y-580617D01*
X-811300Y-580500D01*
X-810633Y-580617D01*
X-810050Y-581083D01*
X-809550Y-581783D01*
X-809217Y-582600D01*
X-809050Y-583533D01*
Y-584467D01*
X-809217Y-585400D01*
X-809550Y-586217D01*
X-810050Y-586917D01*
X-810633Y-587383D01*
X-811300Y-587500D01*
G01X-806083D02*
Y-580500D01*
X-802917D01*
G01X-804083Y-583883D02*
X-806083D01*
G01X-797700Y-580500D02*
Y-587500D01*
G01X-799617Y-580500D02*
X-795783D01*
G01X-782267Y-581083D02*
X-782767Y-580733D01*
X-783350Y-580500D01*
X-784017D01*
X-784767Y-580850D01*
X-785350Y-581433D01*
X-785767Y-582133D01*
X-786100Y-583300D01*
X-786183Y-584350D01*
X-786017Y-585400D01*
X-785767Y-586100D01*
X-785267Y-586800D01*
X-784683Y-587267D01*
X-784100Y-587500D01*
X-783517D01*
X-782933Y-587267D01*
X-782433Y-586917D01*
X-782017Y-586450D01*
G01X-777300Y-587500D02*
X-777967Y-587383D01*
X-778550Y-586917D01*
X-779050Y-586217D01*
X-779383Y-585400D01*
X-779550Y-584467D01*
Y-583533D01*
X-779383Y-582600D01*
X-779050Y-581783D01*
X-778550Y-581083D01*
X-777967Y-580617D01*
X-777300Y-580500D01*
X-776633Y-580617D01*
X-776050Y-581083D01*
X-775550Y-581783D01*
X-775217Y-582600D01*
X-775050Y-583533D01*
Y-584467D01*
X-775217Y-585400D01*
X-775550Y-586217D01*
X-776050Y-586917D01*
X-776633Y-587383D01*
X-777300Y-587500D01*
G01X-772167D02*
Y-580500D01*
X-770083D01*
X-769417Y-580850D01*
X-769000Y-581317D01*
X-768833Y-582250D01*
X-769000Y-583183D01*
X-769500Y-583767D01*
X-770083Y-584117D01*
X-772167D01*
G01X-770083D02*
X-768833Y-587500D01*
G01X-765367D02*
Y-580500D01*
X-763367D01*
X-762700Y-580850D01*
X-762200Y-581667D01*
X-762033Y-582600D01*
X-762200Y-583533D01*
X-762617Y-584233D01*
X-763367Y-584584D01*
X-765367D01*
G01X-756900Y-587500D02*
X-757567Y-587383D01*
X-758150Y-586917D01*
X-758650Y-586217D01*
X-758983Y-585400D01*
X-759150Y-584467D01*
Y-583533D01*
X-758983Y-582600D01*
X-758650Y-581783D01*
X-758150Y-581083D01*
X-757567Y-580617D01*
X-756900Y-580500D01*
X-756233Y-580617D01*
X-755650Y-581083D01*
X-755150Y-581783D01*
X-754817Y-582600D01*
X-754650Y-583533D01*
Y-584467D01*
X-754817Y-585400D01*
X-755150Y-586217D01*
X-755650Y-586917D01*
X-756233Y-587383D01*
X-756900Y-587500D01*
G01X-751767D02*
Y-580500D01*
X-749683D01*
X-749017Y-580850D01*
X-748600Y-581317D01*
X-748433Y-582250D01*
X-748600Y-583183D01*
X-749100Y-583767D01*
X-749683Y-584117D01*
X-751767D01*
G01X-749683D02*
X-748433Y-587500D01*
G01X-745383D02*
X-743300Y-580500D01*
X-741217Y-587500D01*
G01X-741967Y-585050D02*
X-744633D01*
G01X-736500Y-580500D02*
Y-587500D01*
G01X-738417Y-580500D02*
X-734583D01*
G01X-730700D02*
X-728700D01*
G01X-729700D02*
Y-587500D01*
G01X-730700D02*
X-728700D01*
G01X-722900D02*
X-723567Y-587383D01*
X-724150Y-586917D01*
X-724650Y-586217D01*
X-724983Y-585400D01*
X-725150Y-584467D01*
Y-583533D01*
X-724983Y-582600D01*
X-724650Y-581783D01*
X-724150Y-581083D01*
X-723567Y-580617D01*
X-722900Y-580500D01*
X-722233Y-580617D01*
X-721650Y-581083D01*
X-721150Y-581783D01*
X-720817Y-582600D01*
X-720650Y-583533D01*
Y-584467D01*
X-720817Y-585400D01*
X-721150Y-586217D01*
X-721650Y-586917D01*
X-722233Y-587383D01*
X-722900Y-587500D01*
G01X-718017D02*
Y-580500D01*
X-714183Y-587500D01*
Y-580500D01*
G01X-709300Y-587733D02*
X-709467Y-587617D01*
Y-587383D01*
X-709300Y-587267D01*
X-709133Y-587383D01*
Y-587617D01*
X-709300Y-587733D01*
G01X-870667Y-551083D02*
X-871167Y-550733D01*
X-871750Y-550500D01*
X-872417D01*
X-873167Y-550850D01*
X-873750Y-551433D01*
X-874167Y-552133D01*
X-874500Y-553300D01*
X-874583Y-554350D01*
X-874417Y-555400D01*
X-874167Y-556100D01*
X-873667Y-556800D01*
X-873083Y-557267D01*
X-872500Y-557500D01*
X-871917D01*
X-871333Y-557267D01*
X-870833Y-556917D01*
X-870417Y-556450D01*
G01X-865700Y-557500D02*
X-866367Y-557383D01*
X-866950Y-556917D01*
X-867450Y-556217D01*
X-867783Y-555400D01*
X-867950Y-554467D01*
Y-553533D01*
X-867783Y-552600D01*
X-867450Y-551783D01*
X-866950Y-551083D01*
X-866367Y-550617D01*
X-865700Y-550500D01*
X-865033Y-550617D01*
X-864450Y-551083D01*
X-863950Y-551783D01*
X-863617Y-552600D01*
X-863450Y-553533D01*
Y-554467D01*
X-863617Y-555400D01*
X-863950Y-556217D01*
X-864450Y-556917D01*
X-865033Y-557383D01*
X-865700Y-557500D01*
G01X-860817D02*
Y-550500D01*
X-856983Y-557500D01*
Y-550500D01*
G01X-853683Y-557500D02*
Y-550500D01*
X-850517D01*
G01X-851683Y-553883D02*
X-853683D01*
G01X-846300Y-550500D02*
X-844300D01*
G01X-845300D02*
Y-557500D01*
G01X-846300D02*
X-844300D01*
G01X-840333D02*
Y-550500D01*
X-838667D01*
X-838000Y-550850D01*
X-837500Y-551317D01*
X-837083Y-552017D01*
X-836750Y-552833D01*
X-836667Y-554000D01*
X-836750Y-555167D01*
X-837083Y-555983D01*
X-837500Y-556684D01*
X-838000Y-557150D01*
X-838667Y-557500D01*
X-840333D01*
G01X-830033D02*
X-833367D01*
Y-550500D01*
X-830033D01*
G01X-831367Y-553883D02*
X-833367D01*
G01X-826817Y-557500D02*
Y-550500D01*
X-822983Y-557500D01*
Y-550500D01*
G01X-816267Y-551083D02*
X-816767Y-550733D01*
X-817350Y-550500D01*
X-818017D01*
X-818767Y-550850D01*
X-819350Y-551433D01*
X-819767Y-552133D01*
X-820100Y-553300D01*
X-820183Y-554350D01*
X-820017Y-555400D01*
X-819767Y-556100D01*
X-819267Y-556800D01*
X-818683Y-557267D01*
X-818100Y-557500D01*
X-817517D01*
X-816933Y-557267D01*
X-816433Y-556917D01*
X-816017Y-556450D01*
G01X-809633Y-557500D02*
X-812967D01*
Y-550500D01*
X-809633D01*
G01X-810967Y-553883D02*
X-812967D01*
G01X-799783Y-557500D02*
X-797700Y-550500D01*
X-795617Y-557500D01*
G01X-796367Y-555050D02*
X-799033D01*
G01X-792817Y-557500D02*
Y-550500D01*
X-788983Y-557500D01*
Y-550500D01*
G01X-785933Y-557500D02*
Y-550500D01*
X-784267D01*
X-783600Y-550850D01*
X-783100Y-551317D01*
X-782683Y-552017D01*
X-782350Y-552833D01*
X-782267Y-554000D01*
X-782350Y-555167D01*
X-782683Y-555983D01*
X-783100Y-556684D01*
X-783600Y-557150D01*
X-784267Y-557500D01*
X-785933D01*
G01X-771500Y-550500D02*
X-769500D01*
G01X-770500D02*
Y-557500D01*
G01X-771500D02*
X-769500D01*
G01X-763700Y-550500D02*
Y-557500D01*
G01X-765617Y-550500D02*
X-761783D01*
G01X-758650Y-556567D02*
X-757983Y-557150D01*
X-757233Y-557500D01*
X-756567D01*
X-755900Y-557150D01*
X-755400Y-556567D01*
X-755150Y-555750D01*
X-755317Y-554933D01*
X-755733Y-554233D01*
X-756483Y-553767D01*
X-757483Y-553533D01*
X-758067Y-553067D01*
X-758317Y-552250D01*
X-758150Y-551433D01*
X-757733Y-550850D01*
X-757150Y-550500D01*
X-756567D01*
X-755983Y-550733D01*
X-755483Y-551317D01*
G01X-741467Y-551083D02*
X-741967Y-550733D01*
X-742550Y-550500D01*
X-743217D01*
X-743967Y-550850D01*
X-744550Y-551433D01*
X-744967Y-552133D01*
X-745300Y-553300D01*
X-745383Y-554350D01*
X-745217Y-555400D01*
X-744967Y-556100D01*
X-744467Y-556800D01*
X-743883Y-557267D01*
X-743300Y-557500D01*
X-742717D01*
X-742133Y-557267D01*
X-741633Y-556917D01*
X-741217Y-556450D01*
G01X-736500Y-557500D02*
X-737167Y-557383D01*
X-737750Y-556917D01*
X-738250Y-556217D01*
X-738583Y-555400D01*
X-738750Y-554467D01*
Y-553533D01*
X-738583Y-552600D01*
X-738250Y-551783D01*
X-737750Y-551083D01*
X-737167Y-550617D01*
X-736500Y-550500D01*
X-735833Y-550617D01*
X-735250Y-551083D01*
X-734750Y-551783D01*
X-734417Y-552600D01*
X-734250Y-553533D01*
Y-554467D01*
X-734417Y-555400D01*
X-734750Y-556217D01*
X-735250Y-556917D01*
X-735833Y-557383D01*
X-736500Y-557500D01*
G01X-731617D02*
Y-550500D01*
X-727783Y-557500D01*
Y-550500D01*
G01X-722900D02*
Y-557500D01*
G01X-724817Y-550500D02*
X-720983D01*
G01X-714433Y-557500D02*
X-717767D01*
Y-550500D01*
X-714433D01*
G01X-715767Y-553883D02*
X-717767D01*
G01X-711217Y-557500D02*
Y-550500D01*
X-707383Y-557500D01*
Y-550500D01*
G01X-702500D02*
Y-557500D01*
G01X-704417Y-550500D02*
X-700583D01*
G01X-697450Y-556567D02*
X-696783Y-557150D01*
X-696033Y-557500D01*
X-695367D01*
X-694700Y-557150D01*
X-694200Y-556567D01*
X-693950Y-555750D01*
X-694117Y-554933D01*
X-694533Y-554233D01*
X-695283Y-553767D01*
X-696283Y-553533D01*
X-696867Y-553067D01*
X-697117Y-552250D01*
X-696950Y-551433D01*
X-696533Y-550850D01*
X-695950Y-550500D01*
X-695367D01*
X-694783Y-550733D01*
X-694283Y-551317D01*
G01X-684267Y-557500D02*
Y-550500D01*
X-682100Y-556333D01*
X-679933Y-550500D01*
Y-557500D01*
G01X-677383D02*
X-675300Y-550500D01*
X-673217Y-557500D01*
G01X-673967Y-555050D02*
X-676633D01*
G01X-668500Y-557500D02*
Y-554350D01*
X-670167Y-550500D01*
G01X-666833D02*
X-668500Y-554350D01*
G01X-656817Y-557500D02*
Y-550500D01*
X-652983Y-557500D01*
Y-550500D01*
G01X-648100Y-557500D02*
X-648767Y-557383D01*
X-649350Y-556917D01*
X-649850Y-556217D01*
X-650183Y-555400D01*
X-650350Y-554467D01*
Y-553533D01*
X-650183Y-552600D01*
X-649850Y-551783D01*
X-649350Y-551083D01*
X-648767Y-550617D01*
X-648100Y-550500D01*
X-647433Y-550617D01*
X-646850Y-551083D01*
X-646350Y-551783D01*
X-646017Y-552600D01*
X-645850Y-553533D01*
Y-554467D01*
X-646017Y-555400D01*
X-646350Y-556217D01*
X-646850Y-556917D01*
X-647433Y-557383D01*
X-648100Y-557500D01*
G01X-641300Y-550500D02*
Y-557500D01*
G01X-643217Y-550500D02*
X-639383D01*
G01X-627033Y-553767D02*
X-626700Y-553417D01*
X-626450Y-552833D01*
X-626283Y-552017D01*
X-626450Y-551317D01*
X-626783Y-550850D01*
X-627367Y-550500D01*
X-629617D01*
Y-557500D01*
X-626867D01*
X-626283Y-557033D01*
X-625950Y-556333D01*
X-625783Y-555517D01*
X-625950Y-554700D01*
X-626450Y-554000D01*
X-627033Y-553767D01*
X-629617D01*
G01X-619233Y-557500D02*
X-622567D01*
Y-550500D01*
X-619233D01*
G01X-620567Y-553883D02*
X-622567D01*
G01X-870667Y-536083D02*
X-871167Y-535733D01*
X-871750Y-535500D01*
X-872417D01*
X-873167Y-535850D01*
X-873750Y-536433D01*
X-874167Y-537133D01*
X-874500Y-538300D01*
X-874583Y-539350D01*
X-874417Y-540400D01*
X-874167Y-541100D01*
X-873667Y-541800D01*
X-873083Y-542267D01*
X-872500Y-542500D01*
X-871917D01*
X-871333Y-542267D01*
X-870833Y-541917D01*
X-870417Y-541450D01*
G01X-865700Y-542500D02*
X-866367Y-542383D01*
X-866950Y-541917D01*
X-867450Y-541217D01*
X-867783Y-540400D01*
X-867950Y-539467D01*
Y-538533D01*
X-867783Y-537600D01*
X-867450Y-536783D01*
X-866950Y-536083D01*
X-866367Y-535617D01*
X-865700Y-535500D01*
X-865033Y-535617D01*
X-864450Y-536083D01*
X-863950Y-536783D01*
X-863617Y-537600D01*
X-863450Y-538533D01*
Y-539467D01*
X-863617Y-540400D01*
X-863950Y-541217D01*
X-864450Y-541917D01*
X-865033Y-542383D01*
X-865700Y-542500D01*
G01X-860567D02*
Y-535500D01*
X-858483D01*
X-857817Y-535850D01*
X-857400Y-536317D01*
X-857233Y-537250D01*
X-857400Y-538183D01*
X-857900Y-538767D01*
X-858483Y-539117D01*
X-860567D01*
G01X-858483D02*
X-857233Y-542500D01*
G01X-853767D02*
Y-535500D01*
X-851767D01*
X-851100Y-535850D01*
X-850600Y-536667D01*
X-850433Y-537600D01*
X-850600Y-538533D01*
X-851017Y-539233D01*
X-851767Y-539584D01*
X-853767D01*
G01X-845300Y-542500D02*
X-845967Y-542383D01*
X-846550Y-541917D01*
X-847050Y-541217D01*
X-847383Y-540400D01*
X-847550Y-539467D01*
Y-538533D01*
X-847383Y-537600D01*
X-847050Y-536783D01*
X-846550Y-536083D01*
X-845967Y-535617D01*
X-845300Y-535500D01*
X-844633Y-535617D01*
X-844050Y-536083D01*
X-843550Y-536783D01*
X-843217Y-537600D01*
X-843050Y-538533D01*
Y-539467D01*
X-843217Y-540400D01*
X-843550Y-541217D01*
X-844050Y-541917D01*
X-844633Y-542383D01*
X-845300Y-542500D01*
G01X-840167D02*
Y-535500D01*
X-838083D01*
X-837417Y-535850D01*
X-837000Y-536317D01*
X-836833Y-537250D01*
X-837000Y-538183D01*
X-837500Y-538767D01*
X-838083Y-539117D01*
X-840167D01*
G01X-838083D02*
X-836833Y-542500D01*
G01X-833783D02*
X-831700Y-535500D01*
X-829617Y-542500D01*
G01X-830367Y-540050D02*
X-833033D01*
G01X-824900Y-535500D02*
Y-542500D01*
G01X-826817Y-535500D02*
X-822983D01*
G01X-819100D02*
X-817100D01*
G01X-818100D02*
Y-542500D01*
G01X-819100D02*
X-817100D01*
G01X-811300D02*
X-811967Y-542383D01*
X-812550Y-541917D01*
X-813050Y-541217D01*
X-813383Y-540400D01*
X-813550Y-539467D01*
Y-538533D01*
X-813383Y-537600D01*
X-813050Y-536783D01*
X-812550Y-536083D01*
X-811967Y-535617D01*
X-811300Y-535500D01*
X-810633Y-535617D01*
X-810050Y-536083D01*
X-809550Y-536783D01*
X-809217Y-537600D01*
X-809050Y-538533D01*
Y-539467D01*
X-809217Y-540400D01*
X-809550Y-541217D01*
X-810050Y-541917D01*
X-810633Y-542383D01*
X-811300Y-542500D01*
G01X-806417D02*
Y-535500D01*
X-802583Y-542500D01*
Y-535500D01*
G01X-797700Y-542733D02*
X-797867Y-542617D01*
Y-542383D01*
X-797700Y-542267D01*
X-797533Y-542383D01*
Y-542617D01*
X-797700Y-542733D01*
G01X-784100Y-535500D02*
Y-542500D01*
G01X-786017Y-535500D02*
X-782183D01*
G01X-779050Y-542500D02*
Y-535500D01*
G01X-775550D02*
Y-542500D01*
G01Y-539000D02*
X-779050D01*
G01X-771500Y-535500D02*
X-769500D01*
G01X-770500D02*
Y-542500D01*
G01X-771500D02*
X-769500D01*
G01X-765450Y-541567D02*
X-764783Y-542150D01*
X-764033Y-542500D01*
X-763367D01*
X-762700Y-542150D01*
X-762200Y-541567D01*
X-761950Y-540750D01*
X-762117Y-539933D01*
X-762533Y-539233D01*
X-763283Y-538767D01*
X-764283Y-538533D01*
X-764867Y-538067D01*
X-765117Y-537250D01*
X-764950Y-536433D01*
X-764533Y-535850D01*
X-763950Y-535500D01*
X-763367D01*
X-762783Y-535733D01*
X-762283Y-536317D01*
G01X-751933Y-542500D02*
Y-535500D01*
X-750267D01*
X-749600Y-535850D01*
X-749100Y-536317D01*
X-748683Y-537017D01*
X-748350Y-537833D01*
X-748267Y-539000D01*
X-748350Y-540167D01*
X-748683Y-540983D01*
X-749100Y-541684D01*
X-749600Y-542150D01*
X-750267Y-542500D01*
X-751933D01*
G01X-744967D02*
Y-535500D01*
X-742883D01*
X-742217Y-535850D01*
X-741800Y-536317D01*
X-741633Y-537250D01*
X-741800Y-538183D01*
X-742300Y-538767D01*
X-742883Y-539117D01*
X-744967D01*
G01X-742883D02*
X-741633Y-542500D01*
G01X-738583D02*
X-736500Y-535500D01*
X-734417Y-542500D01*
G01X-735167Y-540050D02*
X-737833D01*
G01X-732200Y-535500D02*
X-731033Y-542500D01*
X-729700Y-535500D01*
X-728367Y-542500D01*
X-727200Y-535500D01*
G01X-723900D02*
X-721900D01*
G01X-722900D02*
Y-542500D01*
G01X-723900D02*
X-721900D01*
G01X-718017D02*
Y-535500D01*
X-714183Y-542500D01*
Y-535500D01*
G01X-708800Y-539000D02*
X-707133D01*
Y-541100D01*
X-707633Y-541800D01*
X-708217Y-542267D01*
X-709050Y-542500D01*
X-709883Y-542267D01*
X-710467Y-541800D01*
X-710967Y-541100D01*
X-711300Y-540283D01*
X-711467Y-539350D01*
Y-538533D01*
X-711300Y-537833D01*
X-710967Y-537017D01*
X-710467Y-536317D01*
X-709967Y-535850D01*
X-709300Y-535500D01*
X-708717D01*
X-708050Y-535733D01*
X-707550Y-536200D01*
G01X-696700Y-535500D02*
X-694700D01*
G01X-695700D02*
Y-542500D01*
G01X-696700D02*
X-694700D01*
G01X-690650Y-541567D02*
X-689983Y-542150D01*
X-689233Y-542500D01*
X-688567D01*
X-687900Y-542150D01*
X-687400Y-541567D01*
X-687150Y-540750D01*
X-687317Y-539933D01*
X-687733Y-539233D01*
X-688483Y-538767D01*
X-689483Y-538533D01*
X-690067Y-538067D01*
X-690317Y-537250D01*
X-690150Y-536433D01*
X-689733Y-535850D01*
X-689150Y-535500D01*
X-688567D01*
X-687983Y-535733D01*
X-687483Y-536317D01*
G01X-676967Y-542500D02*
Y-535500D01*
X-674883D01*
X-674217Y-535850D01*
X-673800Y-536317D01*
X-673633Y-537250D01*
X-673800Y-538183D01*
X-674300Y-538767D01*
X-674883Y-539117D01*
X-676967D01*
G01X-674883D02*
X-673633Y-542500D01*
G01X-666833D02*
X-670167D01*
Y-535500D01*
X-666833D01*
G01X-668167Y-538883D02*
X-670167D01*
G01X-659867Y-536083D02*
X-660367Y-535733D01*
X-660950Y-535500D01*
X-661617D01*
X-662367Y-535850D01*
X-662950Y-536433D01*
X-663367Y-537133D01*
X-663700Y-538300D01*
X-663783Y-539350D01*
X-663617Y-540400D01*
X-663367Y-541100D01*
X-662867Y-541800D01*
X-662283Y-542267D01*
X-661700Y-542500D01*
X-661117D01*
X-660533Y-542267D01*
X-660033Y-541917D01*
X-659617Y-541450D01*
G01X-653233Y-542500D02*
X-656567D01*
Y-535500D01*
X-653233D01*
G01X-654567Y-538883D02*
X-656567D01*
G01X-649100Y-535500D02*
X-647100D01*
G01X-648100D02*
Y-542500D01*
G01X-649100D02*
X-647100D01*
G01X-643383Y-535500D02*
X-641300Y-542500D01*
X-639217Y-535500D01*
G01X-632833Y-542500D02*
X-636167D01*
Y-535500D01*
X-632833D01*
G01X-634167Y-538883D02*
X-636167D01*
G01X-629533Y-542500D02*
Y-535500D01*
X-627867D01*
X-627200Y-535850D01*
X-626700Y-536317D01*
X-626283Y-537017D01*
X-625950Y-537833D01*
X-625867Y-539000D01*
X-625950Y-540167D01*
X-626283Y-540983D01*
X-626700Y-541684D01*
X-627200Y-542150D01*
X-627867Y-542500D01*
X-629533D01*
G01X-615100Y-535500D02*
X-613100D01*
G01X-614100D02*
Y-542500D01*
G01X-615100D02*
X-613100D01*
G01X-609217D02*
Y-535500D01*
X-605383Y-542500D01*
Y-535500D01*
G01X-872500Y-520500D02*
Y-527500D01*
G01X-874417Y-520500D02*
X-870583D01*
G01X-867450Y-527500D02*
Y-520500D01*
G01X-863950D02*
Y-527500D01*
G01Y-524000D02*
X-867450D01*
G01X-857233Y-527500D02*
X-860567D01*
Y-520500D01*
X-857233D01*
G01X-858567Y-523883D02*
X-860567D01*
G01X-846967Y-527500D02*
Y-520500D01*
X-844967D01*
X-844300Y-520850D01*
X-843800Y-521667D01*
X-843633Y-522600D01*
X-843800Y-523533D01*
X-844217Y-524233D01*
X-844967Y-524584D01*
X-846967D01*
G01X-840167Y-527500D02*
Y-520500D01*
X-838083D01*
X-837417Y-520850D01*
X-837000Y-521317D01*
X-836833Y-522250D01*
X-837000Y-523183D01*
X-837500Y-523767D01*
X-838083Y-524117D01*
X-840167D01*
G01X-838083D02*
X-836833Y-527500D01*
G01X-831700D02*
X-832367Y-527383D01*
X-832950Y-526917D01*
X-833450Y-526217D01*
X-833783Y-525400D01*
X-833950Y-524467D01*
Y-523533D01*
X-833783Y-522600D01*
X-833450Y-521783D01*
X-832950Y-521083D01*
X-832367Y-520617D01*
X-831700Y-520500D01*
X-831033Y-520617D01*
X-830450Y-521083D01*
X-829950Y-521783D01*
X-829617Y-522600D01*
X-829450Y-523533D01*
Y-524467D01*
X-829617Y-525400D01*
X-829950Y-526217D01*
X-830450Y-526917D01*
X-831033Y-527383D01*
X-831700Y-527500D01*
G01X-826567D02*
Y-520500D01*
X-824567D01*
X-823900Y-520850D01*
X-823400Y-521667D01*
X-823233Y-522600D01*
X-823400Y-523533D01*
X-823817Y-524233D01*
X-824567Y-524584D01*
X-826567D01*
G01X-819767Y-527500D02*
Y-520500D01*
X-817683D01*
X-817017Y-520850D01*
X-816600Y-521317D01*
X-816433Y-522250D01*
X-816600Y-523183D01*
X-817100Y-523767D01*
X-817683Y-524117D01*
X-819767D01*
G01X-817683D02*
X-816433Y-527500D01*
G01X-812300Y-520500D02*
X-810300D01*
G01X-811300D02*
Y-527500D01*
G01X-812300D02*
X-810300D01*
G01X-802833D02*
X-806167D01*
Y-520500D01*
X-802833D01*
G01X-804167Y-523883D02*
X-806167D01*
G01X-797700Y-520500D02*
Y-527500D01*
G01X-799617Y-520500D02*
X-795783D01*
G01X-792983Y-527500D02*
X-790900Y-520500D01*
X-788817Y-527500D01*
G01X-789567Y-525050D02*
X-792233D01*
G01X-785767Y-527500D02*
Y-520500D01*
X-783683D01*
X-783017Y-520850D01*
X-782600Y-521317D01*
X-782433Y-522250D01*
X-782600Y-523183D01*
X-783100Y-523767D01*
X-783683Y-524117D01*
X-785767D01*
G01X-783683D02*
X-782433Y-527500D01*
G01X-777300D02*
Y-524350D01*
X-778967Y-520500D01*
G01X-775633D02*
X-777300Y-524350D01*
G01X-765367Y-527500D02*
Y-520500D01*
X-763367D01*
X-762700Y-520850D01*
X-762200Y-521667D01*
X-762033Y-522600D01*
X-762200Y-523533D01*
X-762617Y-524233D01*
X-763367Y-524584D01*
X-765367D01*
G01X-758567Y-527500D02*
Y-520500D01*
X-756483D01*
X-755817Y-520850D01*
X-755400Y-521317D01*
X-755233Y-522250D01*
X-755400Y-523183D01*
X-755900Y-523767D01*
X-756483Y-524117D01*
X-758567D01*
G01X-756483D02*
X-755233Y-527500D01*
G01X-750100D02*
X-750767Y-527383D01*
X-751350Y-526917D01*
X-751850Y-526217D01*
X-752183Y-525400D01*
X-752350Y-524467D01*
Y-523533D01*
X-752183Y-522600D01*
X-751850Y-521783D01*
X-751350Y-521083D01*
X-750767Y-520617D01*
X-750100Y-520500D01*
X-749433Y-520617D01*
X-748850Y-521083D01*
X-748350Y-521783D01*
X-748017Y-522600D01*
X-747850Y-523533D01*
Y-524467D01*
X-748017Y-525400D01*
X-748350Y-526217D01*
X-748850Y-526917D01*
X-749433Y-527383D01*
X-750100Y-527500D01*
G01X-744967D02*
Y-520500D01*
X-742967D01*
X-742300Y-520850D01*
X-741800Y-521667D01*
X-741633Y-522600D01*
X-741800Y-523533D01*
X-742217Y-524233D01*
X-742967Y-524584D01*
X-744967D01*
G01X-734833Y-527500D02*
X-738167D01*
Y-520500D01*
X-734833D01*
G01X-736167Y-523883D02*
X-738167D01*
G01X-731367Y-527500D02*
Y-520500D01*
X-729283D01*
X-728617Y-520850D01*
X-728200Y-521317D01*
X-728033Y-522250D01*
X-728200Y-523183D01*
X-728700Y-523767D01*
X-729283Y-524117D01*
X-731367D01*
G01X-729283D02*
X-728033Y-527500D01*
G01X-722900Y-520500D02*
Y-527500D01*
G01X-724817Y-520500D02*
X-720983D01*
G01X-716100Y-527500D02*
Y-524350D01*
X-717767Y-520500D01*
G01X-714433D02*
X-716100Y-524350D01*
G01X-702500Y-527500D02*
X-703167Y-527383D01*
X-703750Y-526917D01*
X-704250Y-526217D01*
X-704583Y-525400D01*
X-704750Y-524467D01*
Y-523533D01*
X-704583Y-522600D01*
X-704250Y-521783D01*
X-703750Y-521083D01*
X-703167Y-520617D01*
X-702500Y-520500D01*
X-701833Y-520617D01*
X-701250Y-521083D01*
X-700750Y-521783D01*
X-700417Y-522600D01*
X-700250Y-523533D01*
Y-524467D01*
X-700417Y-525400D01*
X-700750Y-526217D01*
X-701250Y-526917D01*
X-701833Y-527383D01*
X-702500Y-527500D01*
G01X-697283D02*
Y-520500D01*
X-694117D01*
G01X-695283Y-523883D02*
X-697283D01*
G01X-684267Y-527500D02*
Y-520500D01*
X-682100Y-526333D01*
X-679933Y-520500D01*
Y-527500D01*
G01X-676300Y-520500D02*
X-674300D01*
G01X-675300D02*
Y-527500D01*
G01X-676300D02*
X-674300D01*
G01X-666667Y-521083D02*
X-667167Y-520733D01*
X-667750Y-520500D01*
X-668417D01*
X-669167Y-520850D01*
X-669750Y-521433D01*
X-670167Y-522133D01*
X-670500Y-523300D01*
X-670583Y-524350D01*
X-670417Y-525400D01*
X-670167Y-526100D01*
X-669667Y-526800D01*
X-669083Y-527267D01*
X-668500Y-527500D01*
X-667917D01*
X-667333Y-527267D01*
X-666833Y-526917D01*
X-666417Y-526450D01*
G01X-663367Y-527500D02*
Y-520500D01*
X-661283D01*
X-660617Y-520850D01*
X-660200Y-521317D01*
X-660033Y-522250D01*
X-660200Y-523183D01*
X-660700Y-523767D01*
X-661283Y-524117D01*
X-663367D01*
G01X-661283D02*
X-660033Y-527500D01*
G01X-654900D02*
X-655567Y-527383D01*
X-656150Y-526917D01*
X-656650Y-526217D01*
X-656983Y-525400D01*
X-657150Y-524467D01*
Y-523533D01*
X-656983Y-522600D01*
X-656650Y-521783D01*
X-656150Y-521083D01*
X-655567Y-520617D01*
X-654900Y-520500D01*
X-654233Y-520617D01*
X-653650Y-521083D01*
X-653150Y-521783D01*
X-652817Y-522600D01*
X-652650Y-523533D01*
Y-524467D01*
X-652817Y-525400D01*
X-653150Y-526217D01*
X-653650Y-526917D01*
X-654233Y-527383D01*
X-654900Y-527500D01*
G01X-649850Y-526567D02*
X-649183Y-527150D01*
X-648433Y-527500D01*
X-647767D01*
X-647100Y-527150D01*
X-646600Y-526567D01*
X-646350Y-525750D01*
X-646517Y-524933D01*
X-646933Y-524233D01*
X-647683Y-523767D01*
X-648683Y-523533D01*
X-649267Y-523067D01*
X-649517Y-522250D01*
X-649350Y-521433D01*
X-648933Y-520850D01*
X-648350Y-520500D01*
X-647767D01*
X-647183Y-520733D01*
X-646683Y-521317D01*
G01X-641300Y-527500D02*
X-641967Y-527383D01*
X-642550Y-526917D01*
X-643050Y-526217D01*
X-643383Y-525400D01*
X-643550Y-524467D01*
Y-523533D01*
X-643383Y-522600D01*
X-643050Y-521783D01*
X-642550Y-521083D01*
X-641967Y-520617D01*
X-641300Y-520500D01*
X-640633Y-520617D01*
X-640050Y-521083D01*
X-639550Y-521783D01*
X-639217Y-522600D01*
X-639050Y-523533D01*
Y-524467D01*
X-639217Y-525400D01*
X-639550Y-526217D01*
X-640050Y-526917D01*
X-640633Y-527383D01*
X-641300Y-527500D01*
G01X-636083D02*
Y-520500D01*
X-632917D01*
G01X-634083Y-523883D02*
X-636083D01*
G01X-627700Y-520500D02*
Y-527500D01*
G01X-629617Y-520500D02*
X-625783D01*
G01X-872500Y-505500D02*
Y-512500D01*
G01X-874417Y-505500D02*
X-870583D01*
G01X-867450Y-512500D02*
Y-505500D01*
G01X-863950D02*
Y-512500D01*
G01Y-509000D02*
X-867450D01*
G01X-859900Y-505500D02*
X-857900D01*
G01X-858900D02*
Y-512500D01*
G01X-859900D02*
X-857900D01*
G01X-853850Y-511567D02*
X-853183Y-512150D01*
X-852433Y-512500D01*
X-851767D01*
X-851100Y-512150D01*
X-850600Y-511567D01*
X-850350Y-510750D01*
X-850517Y-509933D01*
X-850933Y-509233D01*
X-851683Y-508767D01*
X-852683Y-508533D01*
X-853267Y-508067D01*
X-853517Y-507250D01*
X-853350Y-506433D01*
X-852933Y-505850D01*
X-852350Y-505500D01*
X-851767D01*
X-851183Y-505733D01*
X-850683Y-506317D01*
G01X-840333Y-512500D02*
Y-505500D01*
X-838667D01*
X-838000Y-505850D01*
X-837500Y-506317D01*
X-837083Y-507017D01*
X-836750Y-507833D01*
X-836667Y-509000D01*
X-836750Y-510167D01*
X-837083Y-510983D01*
X-837500Y-511684D01*
X-838000Y-512150D01*
X-838667Y-512500D01*
X-840333D01*
G01X-833367D02*
Y-505500D01*
X-831283D01*
X-830617Y-505850D01*
X-830200Y-506317D01*
X-830033Y-507250D01*
X-830200Y-508183D01*
X-830700Y-508767D01*
X-831283Y-509117D01*
X-833367D01*
G01X-831283D02*
X-830033Y-512500D01*
G01X-826983D02*
X-824900Y-505500D01*
X-822817Y-512500D01*
G01X-823567Y-510050D02*
X-826233D01*
G01X-820600Y-505500D02*
X-819433Y-512500D01*
X-818100Y-505500D01*
X-816767Y-512500D01*
X-815600Y-505500D01*
G01X-812300D02*
X-810300D01*
G01X-811300D02*
Y-512500D01*
G01X-812300D02*
X-810300D01*
G01X-806417D02*
Y-505500D01*
X-802583Y-512500D01*
Y-505500D01*
G01X-797200Y-509000D02*
X-795533D01*
Y-511100D01*
X-796033Y-511800D01*
X-796617Y-512267D01*
X-797450Y-512500D01*
X-798283Y-512267D01*
X-798867Y-511800D01*
X-799367Y-511100D01*
X-799700Y-510283D01*
X-799867Y-509350D01*
Y-508533D01*
X-799700Y-507833D01*
X-799367Y-507017D01*
X-798867Y-506317D01*
X-798367Y-505850D01*
X-797700Y-505500D01*
X-797117D01*
X-796450Y-505733D01*
X-795950Y-506200D01*
G01X-782267Y-506083D02*
X-782767Y-505733D01*
X-783350Y-505500D01*
X-784017D01*
X-784767Y-505850D01*
X-785350Y-506433D01*
X-785767Y-507133D01*
X-786100Y-508300D01*
X-786183Y-509350D01*
X-786017Y-510400D01*
X-785767Y-511100D01*
X-785267Y-511800D01*
X-784683Y-512267D01*
X-784100Y-512500D01*
X-783517D01*
X-782933Y-512267D01*
X-782433Y-511917D01*
X-782017Y-511450D01*
G01X-777300Y-512500D02*
X-777967Y-512383D01*
X-778550Y-511917D01*
X-779050Y-511217D01*
X-779383Y-510400D01*
X-779550Y-509467D01*
Y-508533D01*
X-779383Y-507600D01*
X-779050Y-506783D01*
X-778550Y-506083D01*
X-777967Y-505617D01*
X-777300Y-505500D01*
X-776633Y-505617D01*
X-776050Y-506083D01*
X-775550Y-506783D01*
X-775217Y-507600D01*
X-775050Y-508533D01*
Y-509467D01*
X-775217Y-510400D01*
X-775550Y-511217D01*
X-776050Y-511917D01*
X-776633Y-512383D01*
X-777300Y-512500D01*
G01X-772417D02*
Y-505500D01*
X-768583Y-512500D01*
Y-505500D01*
G01X-763700D02*
Y-512500D01*
G01X-765617Y-505500D02*
X-761783D01*
G01X-758983Y-512500D02*
X-756900Y-505500D01*
X-754817Y-512500D01*
G01X-755567Y-510050D02*
X-758233D01*
G01X-751100Y-505500D02*
X-749100D01*
G01X-750100D02*
Y-512500D01*
G01X-751100D02*
X-749100D01*
G01X-745217D02*
Y-505500D01*
X-741383Y-512500D01*
Y-505500D01*
G01X-738250Y-511567D02*
X-737583Y-512150D01*
X-736833Y-512500D01*
X-736167D01*
X-735500Y-512150D01*
X-735000Y-511567D01*
X-734750Y-510750D01*
X-734917Y-509933D01*
X-735333Y-509233D01*
X-736083Y-508767D01*
X-737083Y-508533D01*
X-737667Y-508067D01*
X-737917Y-507250D01*
X-737750Y-506433D01*
X-737333Y-505850D01*
X-736750Y-505500D01*
X-736167D01*
X-735583Y-505733D01*
X-735083Y-506317D01*
G01X-723900Y-505500D02*
X-721900D01*
G01X-722900D02*
Y-512500D01*
G01X-723900D02*
X-721900D01*
G01X-718017D02*
Y-505500D01*
X-714183Y-512500D01*
Y-505500D01*
G01X-710883Y-512500D02*
Y-505500D01*
X-707717D01*
G01X-708883Y-508883D02*
X-710883D01*
G01X-702500Y-512500D02*
X-703167Y-512383D01*
X-703750Y-511917D01*
X-704250Y-511217D01*
X-704583Y-510400D01*
X-704750Y-509467D01*
Y-508533D01*
X-704583Y-507600D01*
X-704250Y-506783D01*
X-703750Y-506083D01*
X-703167Y-505617D01*
X-702500Y-505500D01*
X-701833Y-505617D01*
X-701250Y-506083D01*
X-700750Y-506783D01*
X-700417Y-507600D01*
X-700250Y-508533D01*
Y-509467D01*
X-700417Y-510400D01*
X-700750Y-511217D01*
X-701250Y-511917D01*
X-701833Y-512383D01*
X-702500Y-512500D01*
G01X-697367D02*
Y-505500D01*
X-695283D01*
X-694617Y-505850D01*
X-694200Y-506317D01*
X-694033Y-507250D01*
X-694200Y-508183D01*
X-694700Y-508767D01*
X-695283Y-509117D01*
X-697367D01*
G01X-695283D02*
X-694033Y-512500D01*
G01X-691067D02*
Y-505500D01*
X-688900Y-511333D01*
X-686733Y-505500D01*
Y-512500D01*
G01X-684183D02*
X-682100Y-505500D01*
X-680017Y-512500D01*
G01X-680767Y-510050D02*
X-683433D01*
G01X-675300Y-505500D02*
Y-512500D01*
G01X-677217Y-505500D02*
X-673383D01*
G01X-669500D02*
X-667500D01*
G01X-668500D02*
Y-512500D01*
G01X-669500D02*
X-667500D01*
G01X-661700D02*
X-662367Y-512383D01*
X-662950Y-511917D01*
X-663450Y-511217D01*
X-663783Y-510400D01*
X-663950Y-509467D01*
Y-508533D01*
X-663783Y-507600D01*
X-663450Y-506783D01*
X-662950Y-506083D01*
X-662367Y-505617D01*
X-661700Y-505500D01*
X-661033Y-505617D01*
X-660450Y-506083D01*
X-659950Y-506783D01*
X-659617Y-507600D01*
X-659450Y-508533D01*
Y-509467D01*
X-659617Y-510400D01*
X-659950Y-511217D01*
X-660450Y-511917D01*
X-661033Y-512383D01*
X-661700Y-512500D01*
G01X-656817D02*
Y-505500D01*
X-652983Y-512500D01*
Y-505500D01*
G01X-643800D02*
X-642633Y-512500D01*
X-641300Y-505500D01*
X-639967Y-512500D01*
X-638800Y-505500D01*
G01X-636250Y-512500D02*
Y-505500D01*
G01X-632750D02*
Y-512500D01*
G01Y-509000D02*
X-636250D01*
G01X-628700Y-505500D02*
X-626700D01*
G01X-627700D02*
Y-512500D01*
G01X-628700D02*
X-626700D01*
G01X-619067Y-506083D02*
X-619567Y-505733D01*
X-620150Y-505500D01*
X-620817D01*
X-621567Y-505850D01*
X-622150Y-506433D01*
X-622567Y-507133D01*
X-622900Y-508300D01*
X-622983Y-509350D01*
X-622817Y-510400D01*
X-622567Y-511100D01*
X-622067Y-511800D01*
X-621483Y-512267D01*
X-620900Y-512500D01*
X-620317D01*
X-619733Y-512267D01*
X-619233Y-511917D01*
X-618817Y-511450D01*
G01X-615850Y-512500D02*
Y-505500D01*
G01X-612350D02*
Y-512500D01*
G01Y-509000D02*
X-615850D01*
G01X-601500Y-505500D02*
X-599500D01*
G01X-600500D02*
Y-512500D01*
G01X-601500D02*
X-599500D01*
G01X-595450Y-511567D02*
X-594783Y-512150D01*
X-594033Y-512500D01*
X-593367D01*
X-592700Y-512150D01*
X-592200Y-511567D01*
X-591950Y-510750D01*
X-592117Y-509933D01*
X-592533Y-509233D01*
X-593283Y-508767D01*
X-594283Y-508533D01*
X-594867Y-508067D01*
X-595117Y-507250D01*
X-594950Y-506433D01*
X-594533Y-505850D01*
X-593950Y-505500D01*
X-593367D01*
X-592783Y-505733D01*
X-592283Y-506317D01*
G01X-858133Y-452500D02*
Y-445500D01*
X-856467D01*
X-855800Y-445850D01*
X-855300Y-446317D01*
X-854883Y-447017D01*
X-854550Y-447833D01*
X-854467Y-449000D01*
X-854550Y-450167D01*
X-854883Y-450983D01*
X-855300Y-451684D01*
X-855800Y-452150D01*
X-856467Y-452500D01*
X-858133D01*
G01X-847833D02*
X-851167D01*
Y-445500D01*
X-847833D01*
G01X-849167Y-448883D02*
X-851167D01*
G01X-844450Y-451567D02*
X-843783Y-452150D01*
X-843033Y-452500D01*
X-842367D01*
X-841700Y-452150D01*
X-841200Y-451567D01*
X-840950Y-450750D01*
X-841117Y-449933D01*
X-841533Y-449233D01*
X-842283Y-448767D01*
X-843283Y-448533D01*
X-843867Y-448067D01*
X-844117Y-447250D01*
X-843950Y-446433D01*
X-843533Y-445850D01*
X-842950Y-445500D01*
X-842367D01*
X-841783Y-445733D01*
X-841283Y-446317D01*
G01X-836900Y-445500D02*
X-834900D01*
G01X-835900D02*
Y-452500D01*
G01X-836900D02*
X-834900D01*
G01X-828600Y-449000D02*
X-826933D01*
Y-451100D01*
X-827433Y-451800D01*
X-828017Y-452267D01*
X-828850Y-452500D01*
X-829683Y-452267D01*
X-830267Y-451800D01*
X-830767Y-451100D01*
X-831100Y-450283D01*
X-831267Y-449350D01*
Y-448533D01*
X-831100Y-447833D01*
X-830767Y-447017D01*
X-830267Y-446317D01*
X-829767Y-445850D01*
X-829100Y-445500D01*
X-828517D01*
X-827850Y-445733D01*
X-827350Y-446200D01*
G01X-824217Y-452500D02*
Y-445500D01*
X-820383Y-452500D01*
Y-445500D01*
G01X-813833Y-452500D02*
X-817167D01*
Y-445500D01*
X-813833D01*
G01X-815167Y-448883D02*
X-817167D01*
G01X-810367Y-452500D02*
Y-445500D01*
X-808283D01*
X-807617Y-445850D01*
X-807200Y-446317D01*
X-807033Y-447250D01*
X-807200Y-448183D01*
X-807700Y-448767D01*
X-808283Y-449117D01*
X-810367D01*
G01X-808283D02*
X-807033Y-452500D01*
G01X-858133D02*
Y-445500D01*
X-856467D01*
X-855800Y-445850D01*
X-855300Y-446317D01*
X-854883Y-447017D01*
X-854550Y-447833D01*
X-854467Y-449000D01*
X-854550Y-450167D01*
X-854883Y-450983D01*
X-855300Y-451684D01*
X-855800Y-452150D01*
X-856467Y-452500D01*
X-858133D01*
G01X-847833D02*
X-851167D01*
Y-445500D01*
X-847833D01*
G01X-849167Y-448883D02*
X-851167D01*
G01X-844450Y-451567D02*
X-843783Y-452150D01*
X-843033Y-452500D01*
X-842367D01*
X-841700Y-452150D01*
X-841200Y-451567D01*
X-840950Y-450750D01*
X-841117Y-449933D01*
X-841533Y-449233D01*
X-842283Y-448767D01*
X-843283Y-448533D01*
X-843867Y-448067D01*
X-844117Y-447250D01*
X-843950Y-446433D01*
X-843533Y-445850D01*
X-842950Y-445500D01*
X-842367D01*
X-841783Y-445733D01*
X-841283Y-446317D01*
G01X-836900Y-445500D02*
X-834900D01*
G01X-835900D02*
Y-452500D01*
G01X-836900D02*
X-834900D01*
G01X-828600Y-449000D02*
X-826933D01*
Y-451100D01*
X-827433Y-451800D01*
X-828017Y-452267D01*
X-828850Y-452500D01*
X-829683Y-452267D01*
X-830267Y-451800D01*
X-830767Y-451100D01*
X-831100Y-450283D01*
X-831267Y-449350D01*
Y-448533D01*
X-831100Y-447833D01*
X-830767Y-447017D01*
X-830267Y-446317D01*
X-829767Y-445850D01*
X-829100Y-445500D01*
X-828517D01*
X-827850Y-445733D01*
X-827350Y-446200D01*
G01X-824217Y-452500D02*
Y-445500D01*
X-820383Y-452500D01*
Y-445500D01*
G01X-813833Y-452500D02*
X-817167D01*
Y-445500D01*
X-813833D01*
G01X-815167Y-448883D02*
X-817167D01*
G01X-810367Y-452500D02*
Y-445500D01*
X-808283D01*
X-807617Y-445850D01*
X-807200Y-446317D01*
X-807033Y-447250D01*
X-807200Y-448183D01*
X-807700Y-448767D01*
X-808283Y-449117D01*
X-810367D01*
G01X-808283D02*
X-807033Y-452500D01*
G01X-642033Y-455000D02*
Y-448000D01*
X-640367D01*
X-639700Y-448350D01*
X-639200Y-448817D01*
X-638783Y-449517D01*
X-638450Y-450333D01*
X-638367Y-451500D01*
X-638450Y-452667D01*
X-638783Y-453483D01*
X-639200Y-454184D01*
X-639700Y-454650D01*
X-640367Y-455000D01*
X-642033D01*
G01X-635483D02*
X-633400Y-448000D01*
X-631317Y-455000D01*
G01X-632067Y-452550D02*
X-634733D01*
G01X-626600Y-448000D02*
Y-455000D01*
G01X-628517Y-448000D02*
X-624683D01*
G01X-618133Y-455000D02*
X-621467D01*
Y-448000D01*
X-618133D01*
G01X-619467Y-451383D02*
X-621467D01*
G54D29*
X-806854Y-99635D03*
Y-83100D03*
X-785200Y-99635D03*
G54D39*
G01X-1020800Y-457700D02*
G02X-1020300Y-458200I0J-500D01*
G01Y-458400D01*
G02X-1020900Y-459000I-600J0D01*
G01X-1021300D01*
G01X-1021800Y-460500D02*
Y-457700D01*
X-1020600D01*
G01X-1018340Y-459100D02*
G03I-2660J0D01*
G01X-1020700D02*
X-1020200Y-460500D01*
M02*
